FILE_TYPE = MACRO_DRAWING;
SET COLOR_WIRE YELLOW;
SET COLOR_PROP ORANGE;
SET COLOR_DOT WHITE;
SET COLOR_ARC YELLOW;
SET COLOR_BODY GREEN;
SET COLOR_NOTE PURPLE;
SET PROP_DISPLAY VALUE;
SET PAGE_NUMBER P137;
FORCEADD UNIVERSAL_POWER..1
R 2
(-6400 2025);
FORCEPROP 3 LASTPIN (-6400 1975) SIG_NAME P3V3_STBY\g
J 0
(-6390 1985);
DISPLAY 0.659574 (-6390 1985);
PAINT MONO (-6390 1985);
DISPLAY INVISIBLE (-6390 1985);
FORCEPROP 1 LAST HDL_POWER P3V3_STBY
J 1
(-6400 2075);
DISPLAY 0.489362 (-6400 2075);
PAINT GREEN (-6400 2075);
FORCEPROP 2 LAST CDS_LIB pure_quanta_power
J 0
(-6400 2025);
DISPLAY INVISIBLE (-6400 2025);
FORCEPROP 1 LAST PATH I160
J 2
(-6450 2050);
DISPLAY 0.872340 (-6450 2050);
PAINT AQUA (-6450 2050);
DISPLAY INVISIBLE (-6450 2050);
FORCEADD Q_CAP..1
(-6575 1750);
FORCEPROP 1 LAST LOCATION C23
J 2
(-6625 1900);
DISPLAY 0.489362 (-6625 1900);
PAINT SKYBLUE (-6625 1900);
FORCEPROP 0 LAST $SEC 1
J 0
(-6625 1950);
DISPLAY 0.680851 (-6625 1950);
PAINT MONO (-6625 1950);
DISPLAY INVISIBLE (-6625 1950);
FORCEPROP 0 LAST CDS_SEC 1
J 0
(-6625 1950);
DISPLAY 1.021277 (-6625 1950);
DISPLAY INVISIBLE (-6625 1950);
FORCEPROP 1 LASTPIN (-6575 1850) $PN 1
J 0
(-6565 1830);
DISPLAY 0.489362 (-6565 1830);
PAINT MONO (-6565 1830);
FORCEPROP 1 LASTPIN (-6575 1650) $PN 2
J 0
(-6565 1630);
DISPLAY 0.489362 (-6565 1630);
PAINT MONO (-6565 1630);
FORCEPROP 1 LAST VALUE 0.1UF
J 2
(-6625 1850);
DISPLAY 0.489362 (-6625 1850);
PAINT SKYBLUE (-6625 1850);
FORCEPROP 1 LAST PACK_TYPE 0402
J 2
(-6625 1650);
DISPLAY 0.489362 (-6625 1650);
PAINT SKYBLUE (-6625 1650);
FORCEPROP 1 LAST MATERIAL X7R
J 2
(-6625 1700);
DISPLAY 0.489362 (-6625 1700);
PAINT SKYBLUE (-6625 1700);
FORCEPROP 1 LAST VOLTAGE 25V
J 2
(-6625 1800);
DISPLAY 0.489362 (-6625 1800);
PAINT SKYBLUE (-6625 1800);
FORCEPROP 1 LAST TOLERANCE 10%
J 2
(-6625 1750);
DISPLAY 0.489362 (-6625 1750);
PAINT SKYBLUE (-6625 1750);
FORCEPROP 2 LAST CDS_LIB pure_quanta
J 0
(-6575 1750);
DISPLAY INVISIBLE (-6575 1750);
FORCEPROP 1 LAST PATH I161
J 0
(-6525 1900);
DISPLAY 0.978723 (-6525 1900);
PAINT WHITE (-6525 1900);
DISPLAY INVISIBLE (-6525 1900);
FORCEPROP 1 LAST PART_NUMBER CH4104K1B00
J 0
(-6525 1600);
DISPLAY 0.489362 (-6525 1600);
PAINT SKYBLUE (-6525 1600);
DISPLAY INVISIBLE (-6525 1600);
FORCEADD UNIVERSAL_GND..1
(-6575 1550);
FORCEPROP 3 LASTPIN (-6575 1600) SIG_NAME GND\g
J 0
(-6565 1610);
DISPLAY 0.659574 (-6565 1610);
PAINT MONO (-6565 1610);
DISPLAY INVISIBLE (-6565 1610);
FORCEPROP 2 LAST CDS_LIB pure_quanta_power
J 0
(-6575 1550);
DISPLAY INVISIBLE (-6575 1550);
FORCEPROP 1 LAST PATH I162
J 0
(-6500 1550);
DISPLAY 0.872340 (-6500 1550);
PAINT AQUA (-6500 1550);
DISPLAY INVISIBLE (-6500 1550);
FORCEPROP 1 LAST HDL_POWER GND
J 1
(-6550 1475);
DISPLAY 0.872340 (-6550 1475);
PAINT GREEN (-6550 1475);
DISPLAY INVISIBLE (-6550 1475);
FORCEADD UNIVERSAL_GND..1
(-5250 1550);
FORCEPROP 3 LASTPIN (-5250 1600) SIG_NAME GND\g
J 0
(-5240 1610);
DISPLAY 0.659574 (-5240 1610);
PAINT MONO (-5240 1610);
DISPLAY INVISIBLE (-5240 1610);
FORCEPROP 2 LAST CDS_LIB pure_quanta_power
J 0
(-5250 1550);
DISPLAY INVISIBLE (-5250 1550);
FORCEPROP 1 LAST PATH I163
J 0
(-5175 1550);
DISPLAY 0.872340 (-5175 1550);
PAINT AQUA (-5175 1550);
DISPLAY INVISIBLE (-5175 1550);
FORCEPROP 1 LAST HDL_POWER GND
J 1
(-5225 1475);
DISPLAY 0.872340 (-5225 1475);
PAINT GREEN (-5225 1475);
DISPLAY INVISIBLE (-5225 1475);
FORCEADD Q_CAP..1
(-5250 1750);
FORCEPROP 1 LAST LOCATION C26
J 0
(-5200 1875);
DISPLAY 0.489362 (-5200 1875);
PAINT SKYBLUE (-5200 1875);
FORCEPROP 0 LAST $SEC 1
J 0
(-5200 1950);
DISPLAY 0.680851 (-5200 1950);
PAINT MONO (-5200 1950);
DISPLAY INVISIBLE (-5200 1950);
FORCEPROP 0 LAST CDS_SEC 1
J 0
(-5200 1950);
DISPLAY 1.021277 (-5200 1950);
DISPLAY INVISIBLE (-5200 1950);
FORCEPROP 1 LASTPIN (-5250 1850) $PN 1
J 0
(-5240 1830);
DISPLAY 0.489362 (-5240 1830);
PAINT MONO (-5240 1830);
FORCEPROP 1 LASTPIN (-5250 1650) $PN 2
J 0
(-5240 1630);
DISPLAY 0.489362 (-5240 1630);
PAINT MONO (-5240 1630);
FORCEPROP 1 LAST VOLTAGE 25V
J 0
(-5200 1800);
DISPLAY 0.489362 (-5200 1800);
PAINT SKYBLUE (-5200 1800);
FORCEPROP 1 LAST PACK_TYPE 0402
J 0
(-5200 1650);
DISPLAY 0.489362 (-5200 1650);
PAINT SKYBLUE (-5200 1650);
FORCEPROP 1 LAST MATERIAL X7R
J 0
(-5200 1700);
DISPLAY 0.489362 (-5200 1700);
PAINT SKYBLUE (-5200 1700);
FORCEPROP 1 LAST VALUE 0.1UF
J 0
(-5200 1850);
DISPLAY 0.489362 (-5200 1850);
PAINT SKYBLUE (-5200 1850);
FORCEPROP 1 LAST TOLERANCE 10%
J 0
(-5200 1750);
DISPLAY 0.489362 (-5200 1750);
PAINT SKYBLUE (-5200 1750);
FORCEPROP 2 LAST CDS_LIB pure_quanta
J 0
(-5250 1750);
DISPLAY INVISIBLE (-5250 1750);
FORCEPROP 1 LAST PATH I164
J 0
(-5200 1900);
DISPLAY 0.978723 (-5200 1900);
PAINT WHITE (-5200 1900);
DISPLAY INVISIBLE (-5200 1900);
FORCEPROP 1 LAST PART_NUMBER CH4104K1B00
J 0
(-5200 1600);
DISPLAY 0.489362 (-5200 1600);
PAINT SKYBLUE (-5200 1600);
DISPLAY INVISIBLE (-5200 1600);
FORCEADD VCC_CORE..1
(-5325 2000);
FORCEPROP 3 LASTPIN (-5325 1950) SIG_NAME P3V3\g
J 0
(-5315 1960);
DISPLAY 0.659574 (-5315 1960);
PAINT MONO (-5315 1960);
DISPLAY INVISIBLE (-5315 1960);
FORCEPROP 1 LAST HDL_POWER P3V3
J 1
(-5325 2050);
DISPLAY 0.489362 (-5325 2050);
PAINT GREEN (-5325 2050);
FORCEPROP 2 LAST CDS_LIB pure_quanta_power
J 0
(-5325 2000);
DISPLAY INVISIBLE (-5325 2000);
FORCEPROP 1 LAST PATH I165
J 0
(-5275 2025);
DISPLAY 0.872340 (-5275 2025);
PAINT AQUA (-5275 2025);
DISPLAY INVISIBLE (-5275 2025);
FORCEADD OFFPAGE..3
R 2
(-7900 1250);
FORCEPROP 2 LAST $XR1 118 
J 0
(-8300 1250);
DISPLAY 0.638298 (-8300 1250);
PAINT MONO (-8300 1250);
FORCEPROP 2 LAST $XR0 117 
J 0
(-8180 1250);
DISPLAY 0.638298 (-8180 1250);
PAINT MONO (-8180 1250);
FORCEPROP 2 LAST PATH I181
J 0
(-8200 1300);
DISPLAY 0.680851 (-8200 1300);
DISPLAY INVISIBLE (-8200 1300);
FORCEPROP 2 LAST CDS_LIB standard
J 0
(-7900 1250);
DISPLAY INVISIBLE (-7900 1250);
FORCEPROP 1 LAST OFFPAGE TRUE
J 2
(-8225 1125);
DISPLAY 0.872340 (-8225 1125);
PAINT GREEN (-8225 1125);
DISPLAY INVISIBLE (-8225 1125);
FORCEPROP 1 LAST COMMENT_BODY TRUE
J 2
(-7850 1150);
DISPLAY 0.872340 (-7850 1150);
PAINT GREEN (-7850 1150);
DISPLAY INVISIBLE (-7850 1150);
FORCEADD OFFPAGE..1
(-7950 1350);
FORCEPROP 2 LAST $XR1 118 
J 0
(-8322 1350);
DISPLAY 0.638298 (-8322 1350);
PAINT MONO (-8322 1350);
FORCEPROP 2 LAST $XR0 117 
J 0
(-8202 1350);
DISPLAY 0.638298 (-8202 1350);
PAINT MONO (-8202 1350);
FORCEPROP 2 LAST PATH I182
J 0
(-8225 1400);
DISPLAY 0.680851 (-8225 1400);
DISPLAY INVISIBLE (-8225 1400);
FORCEPROP 2 LAST CDS_LIB standard
J 0
(-7950 1350);
DISPLAY INVISIBLE (-7950 1350);
FORCEPROP 1 LAST OFFPAGE TRUE
J 0
(-7625 1225);
DISPLAY 0.872340 (-7625 1225);
PAINT GREEN (-7625 1225);
DISPLAY INVISIBLE (-7625 1225);
FORCEPROP 1 LAST COMMENT_BODY TRUE
J 0
(-7825 1250);
DISPLAY 0.872340 (-7825 1250);
PAINT GREEN (-7825 1250);
DISPLAY INVISIBLE (-7825 1250);
FORCEADD OFFPAGE..2
(-3150 1350);
FORCEPROP 2 LAST $XR1 138 
J 0
(-2841 1350);
DISPLAY 0.638298 (-2841 1350);
PAINT MONO (-2841 1350);
FORCEPROP 2 LAST $XR0 137 
J 0
(-2961 1350);
DISPLAY 0.638298 (-2961 1350);
PAINT MONO (-2961 1350);
FORCEPROP 1 LAST COMMENT_BODY TRUE
J 0
(-3195 1255);
DISPLAY 0.872340 (-3195 1255);
PAINT GREEN (-3195 1255);
DISPLAY INVISIBLE (-3195 1255);
FORCEPROP 1 LAST OFFPAGE TRUE
J 0
(-2825 1225);
DISPLAY 0.872340 (-2825 1225);
PAINT GREEN (-2825 1225);
DISPLAY INVISIBLE (-2825 1225);
FORCEPROP 2 LAST CDS_LIB standard
J 0
(-3150 1350);
DISPLAY INVISIBLE (-3150 1350);
FORCEPROP 2 LAST PATH I185
J 0
(-2950 1400);
DISPLAY 0.680851 (-2950 1400);
DISPLAY INVISIBLE (-2950 1400);
FORCEADD Q_RES..1
(-4025 1350);
FORCEPROP 1 LAST LOCATION R1151
J 0
(-4225 1350);
DISPLAY 0.489362 (-4225 1350);
PAINT SKYBLUE (-4225 1350);
FORCEPROP 0 LAST $SEC 1
J 0
(-4150 1400);
DISPLAY 0.680851 (-4150 1400);
PAINT MONO (-4150 1400);
DISPLAY INVISIBLE (-4150 1400);
FORCEPROP 0 LAST CDS_SEC 1
J 0
(-4150 1400);
DISPLAY 1.021277 (-4150 1400);
DISPLAY INVISIBLE (-4150 1400);
FORCEPROP 1 LASTPIN (-4125 1350) $PN 1
J 0
(-4113 1362);
DISPLAY 0.489362 (-4113 1362);
PAINT MONO (-4113 1362);
FORCEPROP 1 LASTPIN (-3925 1350) $PN 2
J 0
(-3963 1362);
DISPLAY 0.489362 (-3963 1362);
PAINT MONO (-3963 1362);
FORCEPROP 1 LAST VALUE 0
J 2
(-3825 1350);
DISPLAY 0.489362 (-3825 1350);
PAINT SKYBLUE (-3825 1350);
FORCEPROP 2 LAST CDS_LIB pure_quanta
J 0
(-4025 1350);
DISPLAY INVISIBLE (-4025 1350);
FORCEPROP 1 LAST PATH I186
J 0
(-4075 1500);
DISPLAY 0.978723 (-4075 1500);
PAINT WHITE (-4075 1500);
DISPLAY INVISIBLE (-4075 1500);
FORCEPROP 1 LAST WATTAGE 1/16W
J 2
(-3625 1275);
DISPLAY 0.489362 (-3625 1275);
PAINT SKYBLUE (-3625 1275);
DISPLAY INVISIBLE (-3625 1275);
FORCEPROP 1 LAST MATERIAL CHIP
J 0
(-3600 1275);
DISPLAY 0.489362 (-3600 1275);
PAINT SKYBLUE (-3600 1275);
DISPLAY INVISIBLE (-3600 1275);
FORCEPROP 1 LAST TOLERANCE 5%
J 0
(-4050 1275);
DISPLAY 0.489362 (-4050 1275);
PAINT SKYBLUE (-4050 1275);
DISPLAY INVISIBLE (-4050 1275);
FORCEPROP 1 LAST PART_NUMBER CS00002JB38
J 0
(-4000 1400);
DISPLAY 0.489362 (-4000 1400);
PAINT SKYBLUE (-4000 1400);
DISPLAY INVISIBLE (-4000 1400);
FORCEPROP 1 LAST PACK_TYPE 0402LF
J 0
(-3975 1275);
DISPLAY 0.489362 (-3975 1275);
PAINT SKYBLUE (-3975 1275);
DISPLAY INVISIBLE (-3975 1275);
FORCEADD OFFPAGE..3
(-3150 1250);
FORCEPROP 2 LAST $XR1 138 
J 0
(-2816 1250);
DISPLAY 0.638298 (-2816 1250);
PAINT MONO (-2816 1250);
FORCEPROP 2 LAST $XR0 137 
J 0
(-2936 1250);
DISPLAY 0.638298 (-2936 1250);
PAINT MONO (-2936 1250);
FORCEPROP 1 LAST COMMENT_BODY TRUE
J 0
(-3200 1150);
DISPLAY 0.872340 (-3200 1150);
PAINT PEACH (-3200 1150);
DISPLAY INVISIBLE (-3200 1150);
FORCEPROP 1 LAST OFFPAGE TRUE
J 0
(-2825 1125);
DISPLAY 0.872340 (-2825 1125);
PAINT GREEN (-2825 1125);
DISPLAY INVISIBLE (-2825 1125);
FORCEPROP 2 LAST CDS_LIB standard
J 0
(-3150 1250);
DISPLAY INVISIBLE (-3150 1250);
FORCEPROP 2 LAST PATH I187
J 0
(-2925 1300);
DISPLAY 0.680851 (-2925 1300);
DISPLAY INVISIBLE (-2925 1300);
FORCEADD Q_RES..1
(-4025 1250);
FORCEPROP 1 LAST LOCATION R1152
J 0
(-4225 1250);
DISPLAY 0.489362 (-4225 1250);
PAINT SKYBLUE (-4225 1250);
FORCEPROP 0 LAST $SEC 1
J 0
(-4150 1300);
DISPLAY 0.680851 (-4150 1300);
PAINT MONO (-4150 1300);
DISPLAY INVISIBLE (-4150 1300);
FORCEPROP 0 LAST CDS_SEC 1
J 0
(-4150 1300);
DISPLAY 1.021277 (-4150 1300);
DISPLAY INVISIBLE (-4150 1300);
FORCEPROP 1 LASTPIN (-4125 1250) $PN 1
J 0
(-4113 1262);
DISPLAY 0.489362 (-4113 1262);
PAINT MONO (-4113 1262);
FORCEPROP 1 LASTPIN (-3925 1250) $PN 2
J 0
(-3963 1262);
DISPLAY 0.489362 (-3963 1262);
PAINT MONO (-3963 1262);
FORCEPROP 1 LAST VALUE 0
J 2
(-3825 1250);
DISPLAY 0.489362 (-3825 1250);
PAINT SKYBLUE (-3825 1250);
FORCEPROP 2 LAST CDS_LIB pure_quanta
J 0
(-4025 1250);
DISPLAY INVISIBLE (-4025 1250);
FORCEPROP 1 LAST PATH I188
J 0
(-4075 1400);
DISPLAY 0.978723 (-4075 1400);
PAINT WHITE (-4075 1400);
DISPLAY INVISIBLE (-4075 1400);
FORCEPROP 1 LAST WATTAGE 1/16W
J 2
(-3625 1175);
DISPLAY 0.489362 (-3625 1175);
PAINT SKYBLUE (-3625 1175);
DISPLAY INVISIBLE (-3625 1175);
FORCEPROP 1 LAST MATERIAL CHIP
J 0
(-3600 1175);
DISPLAY 0.489362 (-3600 1175);
PAINT SKYBLUE (-3600 1175);
DISPLAY INVISIBLE (-3600 1175);
FORCEPROP 1 LAST TOLERANCE 5%
J 0
(-4050 1175);
DISPLAY 0.489362 (-4050 1175);
PAINT SKYBLUE (-4050 1175);
DISPLAY INVISIBLE (-4050 1175);
FORCEPROP 1 LAST PART_NUMBER CS00002JB38
J 0
(-4000 1300);
DISPLAY 0.489362 (-4000 1300);
PAINT SKYBLUE (-4000 1300);
DISPLAY INVISIBLE (-4000 1300);
FORCEPROP 1 LAST PACK_TYPE 0402LF
J 0
(-3975 1175);
DISPLAY 0.489362 (-3975 1175);
PAINT SKYBLUE (-3975 1175);
DISPLAY INVISIBLE (-3975 1175);
FORCEADD OFFPAGE..3
R 2
(-7775 -1475);
FORCEPROP 2 LAST $XR1 118 
J 0
(-8205 -1475);
DISPLAY 0.638298 (-8205 -1475);
PAINT MONO (-8205 -1475);
FORCEPROP 2 LAST $XR0 117 
J 0
(-8085 -1475);
DISPLAY 0.638298 (-8085 -1475);
PAINT MONO (-8085 -1475);
FORCEPROP 2 LAST PATH I189
J 0
(-8075 -1425);
DISPLAY 0.680851 (-8075 -1425);
DISPLAY INVISIBLE (-8075 -1425);
FORCEPROP 1 LAST COMMENT_BODY TRUE
J 2
(-7725 -1575);
DISPLAY 0.872340 (-7725 -1575);
PAINT GREEN (-7725 -1575);
DISPLAY INVISIBLE (-7725 -1575);
FORCEPROP 1 LAST OFFPAGE TRUE
J 2
(-8100 -1600);
DISPLAY 0.872340 (-8100 -1600);
PAINT GREEN (-8100 -1600);
DISPLAY INVISIBLE (-8100 -1600);
FORCEPROP 2 LAST CDS_LIB standard
J 0
(-7775 -1475);
DISPLAY INVISIBLE (-7775 -1475);
FORCEADD OFFPAGE..1
(-7825 -1375);
FORCEPROP 2 LAST $XR1 118 
J 0
(-8197 -1375);
DISPLAY 0.638298 (-8197 -1375);
PAINT MONO (-8197 -1375);
FORCEPROP 2 LAST $XR0 117 
J 0
(-8077 -1375);
DISPLAY 0.638298 (-8077 -1375);
PAINT MONO (-8077 -1375);
FORCEPROP 2 LAST PATH I190
J 0
(-8100 -1325);
DISPLAY 0.680851 (-8100 -1325);
DISPLAY INVISIBLE (-8100 -1325);
FORCEPROP 1 LAST COMMENT_BODY TRUE
J 0
(-7700 -1475);
DISPLAY 0.872340 (-7700 -1475);
PAINT GREEN (-7700 -1475);
DISPLAY INVISIBLE (-7700 -1475);
FORCEPROP 1 LAST OFFPAGE TRUE
J 0
(-7500 -1500);
DISPLAY 0.872340 (-7500 -1500);
PAINT GREEN (-7500 -1500);
DISPLAY INVISIBLE (-7500 -1500);
FORCEPROP 2 LAST CDS_LIB standard
J 0
(-7825 -1375);
DISPLAY INVISIBLE (-7825 -1375);
FORCEADD OFFPAGE..2
(-3050 -1375);
FORCEPROP 2 LAST $XR1 138 
J 0
(-2741 -1375);
DISPLAY 0.638298 (-2741 -1375);
PAINT MONO (-2741 -1375);
FORCEPROP 2 LAST $XR0 137 
J 0
(-2861 -1375);
DISPLAY 0.638298 (-2861 -1375);
PAINT MONO (-2861 -1375);
FORCEPROP 2 LAST CDS_LIB standard
J 0
(-3050 -1375);
DISPLAY INVISIBLE (-3050 -1375);
FORCEPROP 2 LAST PATH I191
J 0
(-2850 -1325);
DISPLAY 0.680851 (-2850 -1325);
DISPLAY INVISIBLE (-2850 -1325);
FORCEPROP 1 LAST COMMENT_BODY TRUE
J 0
(-3095 -1470);
DISPLAY 0.872340 (-3095 -1470);
PAINT GREEN (-3095 -1470);
DISPLAY INVISIBLE (-3095 -1470);
FORCEPROP 1 LAST OFFPAGE TRUE
J 0
(-2725 -1500);
DISPLAY 0.872340 (-2725 -1500);
PAINT GREEN (-2725 -1500);
DISPLAY INVISIBLE (-2725 -1500);
FORCEADD OFFPAGE..3
(-3075 -1475);
FORCEPROP 2 LAST $XR1 138 
J 0
(-2741 -1475);
DISPLAY 0.638298 (-2741 -1475);
PAINT MONO (-2741 -1475);
FORCEPROP 2 LAST $XR0 137 
J 0
(-2861 -1475);
DISPLAY 0.638298 (-2861 -1475);
PAINT MONO (-2861 -1475);
FORCEPROP 1 LAST COMMENT_BODY TRUE
J 0
(-3125 -1575);
DISPLAY 0.872340 (-3125 -1575);
PAINT PEACH (-3125 -1575);
DISPLAY INVISIBLE (-3125 -1575);
FORCEPROP 1 LAST OFFPAGE TRUE
J 0
(-2750 -1600);
DISPLAY 0.872340 (-2750 -1600);
PAINT GREEN (-2750 -1600);
DISPLAY INVISIBLE (-2750 -1600);
FORCEPROP 2 LAST CDS_LIB standard
J 0
(-3075 -1475);
DISPLAY INVISIBLE (-3075 -1475);
FORCEPROP 2 LAST PATH I192
J 0
(-2850 -1425);
DISPLAY 0.680851 (-2850 -1425);
DISPLAY INVISIBLE (-2850 -1425);
FORCEADD Q_RES..1
(-3950 -1375);
FORCEPROP 1 LAST LOCATION R1153
J 0
(-4150 -1375);
DISPLAY 0.489362 (-4150 -1375);
PAINT SKYBLUE (-4150 -1375);
FORCEPROP 0 LAST $SEC 1
J 0
(-4075 -1325);
DISPLAY 0.680851 (-4075 -1325);
PAINT MONO (-4075 -1325);
DISPLAY INVISIBLE (-4075 -1325);
FORCEPROP 0 LAST CDS_SEC 1
J 0
(-4075 -1325);
DISPLAY 1.021277 (-4075 -1325);
DISPLAY INVISIBLE (-4075 -1325);
FORCEPROP 1 LASTPIN (-4050 -1375) $PN 1
J 0
(-4038 -1363);
DISPLAY 0.489362 (-4038 -1363);
PAINT MONO (-4038 -1363);
FORCEPROP 1 LASTPIN (-3850 -1375) $PN 2
J 0
(-3888 -1363);
DISPLAY 0.489362 (-3888 -1363);
PAINT MONO (-3888 -1363);
FORCEPROP 1 LAST VALUE 0
J 2
(-3750 -1375);
DISPLAY 0.489362 (-3750 -1375);
PAINT SKYBLUE (-3750 -1375);
FORCEPROP 2 LAST CDS_LIB pure_quanta
J 0
(-3950 -1375);
DISPLAY INVISIBLE (-3950 -1375);
FORCEPROP 1 LAST PATH I193
J 0
(-4000 -1225);
DISPLAY 0.978723 (-4000 -1225);
PAINT WHITE (-4000 -1225);
DISPLAY INVISIBLE (-4000 -1225);
FORCEPROP 1 LAST WATTAGE 1/16W
J 2
(-3550 -1450);
DISPLAY 0.489362 (-3550 -1450);
PAINT SKYBLUE (-3550 -1450);
DISPLAY INVISIBLE (-3550 -1450);
FORCEPROP 1 LAST MATERIAL CHIP
J 0
(-3525 -1450);
DISPLAY 0.489362 (-3525 -1450);
PAINT SKYBLUE (-3525 -1450);
DISPLAY INVISIBLE (-3525 -1450);
FORCEPROP 1 LAST TOLERANCE 5%
J 0
(-3975 -1450);
DISPLAY 0.489362 (-3975 -1450);
PAINT SKYBLUE (-3975 -1450);
DISPLAY INVISIBLE (-3975 -1450);
FORCEPROP 1 LAST PART_NUMBER CS00002JB38
J 0
(-3925 -1325);
DISPLAY 0.489362 (-3925 -1325);
PAINT SKYBLUE (-3925 -1325);
DISPLAY INVISIBLE (-3925 -1325);
FORCEPROP 1 LAST PACK_TYPE 0402LF
J 0
(-3900 -1450);
DISPLAY 0.489362 (-3900 -1450);
PAINT SKYBLUE (-3900 -1450);
DISPLAY INVISIBLE (-3900 -1450);
FORCEADD Q_RES..1
(-3950 -1475);
FORCEPROP 1 LAST LOCATION R1154
J 0
(-4150 -1475);
DISPLAY 0.489362 (-4150 -1475);
PAINT SKYBLUE (-4150 -1475);
FORCEPROP 0 LAST $SEC 1
J 0
(-4075 -1425);
DISPLAY 0.680851 (-4075 -1425);
PAINT MONO (-4075 -1425);
DISPLAY INVISIBLE (-4075 -1425);
FORCEPROP 0 LAST CDS_SEC 1
J 0
(-4075 -1425);
DISPLAY 1.021277 (-4075 -1425);
DISPLAY INVISIBLE (-4075 -1425);
FORCEPROP 1 LASTPIN (-4050 -1475) $PN 1
J 0
(-4038 -1463);
DISPLAY 0.489362 (-4038 -1463);
PAINT MONO (-4038 -1463);
FORCEPROP 1 LASTPIN (-3850 -1475) $PN 2
J 0
(-3888 -1463);
DISPLAY 0.489362 (-3888 -1463);
PAINT MONO (-3888 -1463);
FORCEPROP 1 LAST VALUE 0
J 2
(-3750 -1475);
DISPLAY 0.489362 (-3750 -1475);
PAINT SKYBLUE (-3750 -1475);
FORCEPROP 2 LAST CDS_LIB pure_quanta
J 0
(-3950 -1475);
DISPLAY INVISIBLE (-3950 -1475);
FORCEPROP 1 LAST PATH I194
J 0
(-4000 -1325);
DISPLAY 0.978723 (-4000 -1325);
PAINT WHITE (-4000 -1325);
DISPLAY INVISIBLE (-4000 -1325);
FORCEPROP 1 LAST WATTAGE 1/16W
J 2
(-3550 -1550);
DISPLAY 0.489362 (-3550 -1550);
PAINT SKYBLUE (-3550 -1550);
DISPLAY INVISIBLE (-3550 -1550);
FORCEPROP 1 LAST MATERIAL CHIP
J 0
(-3525 -1550);
DISPLAY 0.489362 (-3525 -1550);
PAINT SKYBLUE (-3525 -1550);
DISPLAY INVISIBLE (-3525 -1550);
FORCEPROP 1 LAST TOLERANCE 5%
J 0
(-3975 -1550);
DISPLAY 0.489362 (-3975 -1550);
PAINT SKYBLUE (-3975 -1550);
DISPLAY INVISIBLE (-3975 -1550);
FORCEPROP 1 LAST PART_NUMBER CS00002JB38
J 0
(-3925 -1425);
DISPLAY 0.489362 (-3925 -1425);
PAINT SKYBLUE (-3925 -1425);
DISPLAY INVISIBLE (-3925 -1425);
FORCEPROP 1 LAST PACK_TYPE 0402LF
J 0
(-3900 -1550);
DISPLAY 0.489362 (-3900 -1550);
PAINT SKYBLUE (-3900 -1550);
DISPLAY INVISIBLE (-3900 -1550);
FORCEADD UNIVERSAL_POWER..1
R 2
(-6325 -700);
FORCEPROP 3 LASTPIN (-6325 -750) SIG_NAME P3V3_STBY\g
J 0
(-6315 -740);
DISPLAY 0.659574 (-6315 -740);
PAINT MONO (-6315 -740);
DISPLAY INVISIBLE (-6315 -740);
FORCEPROP 1 LAST HDL_POWER P3V3_STBY
J 1
(-6325 -650);
DISPLAY 0.489362 (-6325 -650);
PAINT GREEN (-6325 -650);
FORCEPROP 2 LAST CDS_LIB pure_quanta_power
J 0
(-6325 -700);
DISPLAY INVISIBLE (-6325 -700);
FORCEPROP 1 LAST PATH I195
J 2
(-6375 -675);
DISPLAY 0.872340 (-6375 -675);
PAINT AQUA (-6375 -675);
DISPLAY INVISIBLE (-6375 -675);
FORCEADD Q_CAP..1
(-6500 -975);
FORCEPROP 1 LAST LOCATION C611
J 0
(-6450 -875);
DISPLAY 0.489362 (-6450 -875);
PAINT SKYBLUE (-6450 -875);
FORCEPROP 2 LAST $SEC 1
J 0
(-6450 -775);
DISPLAY 0.680851 (-6450 -775);
PAINT MONO (-6450 -775);
DISPLAY INVISIBLE (-6450 -775);
FORCEPROP 2 LAST CDS_SEC 1
J 0
(-6450 -775);
DISPLAY 0.680851 (-6450 -775);
DISPLAY INVISIBLE (-6450 -775);
FORCEPROP 1 LASTPIN (-6500 -875) $PN 1
J 0
(-6490 -895);
DISPLAY 0.489362 (-6490 -895);
PAINT MONO (-6490 -895);
FORCEPROP 1 LASTPIN (-6500 -1075) $PN 2
J 0
(-6490 -1095);
DISPLAY 0.489362 (-6490 -1095);
PAINT MONO (-6490 -1095);
FORCEPROP 1 LAST MATERIAL X7R
J 2
(-6550 -1025);
DISPLAY 0.489362 (-6550 -1025);
PAINT SKYBLUE (-6550 -1025);
FORCEPROP 1 LAST PACK_TYPE 0402
J 2
(-6550 -1075);
DISPLAY 0.489362 (-6550 -1075);
PAINT SKYBLUE (-6550 -1075);
FORCEPROP 1 LAST VALUE 0.1UF
J 2
(-6550 -875);
DISPLAY 0.489362 (-6550 -875);
PAINT SKYBLUE (-6550 -875);
FORCEPROP 1 LAST VOLTAGE 25V
J 2
(-6550 -925);
DISPLAY 0.489362 (-6550 -925);
PAINT SKYBLUE (-6550 -925);
FORCEPROP 1 LAST TOLERANCE 10%
J 2
(-6550 -975);
DISPLAY 0.489362 (-6550 -975);
PAINT SKYBLUE (-6550 -975);
FORCEPROP 2 LAST CDS_LIB pure_quanta
J 0
(-6500 -975);
DISPLAY INVISIBLE (-6500 -975);
FORCEPROP 1 LAST PATH I196
J 0
(-6450 -825);
DISPLAY 0.978723 (-6450 -825);
PAINT WHITE (-6450 -825);
DISPLAY INVISIBLE (-6450 -825);
FORCEPROP 1 LAST PART_NUMBER CH4104K1B00
J 0
(-6450 -1125);
DISPLAY 0.489362 (-6450 -1125);
PAINT SKYBLUE (-6450 -1125);
DISPLAY INVISIBLE (-6450 -1125);
FORCEADD UNIVERSAL_GND..1
(-6500 -1175);
FORCEPROP 3 LASTPIN (-6500 -1125) SIG_NAME GND\g
J 0
(-6490 -1115);
DISPLAY 0.659574 (-6490 -1115);
PAINT MONO (-6490 -1115);
DISPLAY INVISIBLE (-6490 -1115);
FORCEPROP 2 LAST CDS_LIB pure_quanta_power
J 0
(-6500 -1175);
DISPLAY INVISIBLE (-6500 -1175);
FORCEPROP 1 LAST PATH I197
J 0
(-6425 -1175);
DISPLAY 0.872340 (-6425 -1175);
PAINT AQUA (-6425 -1175);
DISPLAY INVISIBLE (-6425 -1175);
FORCEPROP 1 LAST HDL_POWER GND
J 1
(-6475 -1250);
DISPLAY 0.872340 (-6475 -1250);
PAINT GREEN (-6475 -1250);
DISPLAY INVISIBLE (-6475 -1250);
FORCEADD Q_CAP..1
(-5175 -975);
FORCEPROP 1 LAST LOCATION C612
J 0
(-5125 -825);
DISPLAY 0.489362 (-5125 -825);
PAINT SKYBLUE (-5125 -825);
FORCEPROP 2 LAST $SEC 1
J 0
(-5125 -775);
DISPLAY 0.680851 (-5125 -775);
PAINT MONO (-5125 -775);
DISPLAY INVISIBLE (-5125 -775);
FORCEPROP 2 LAST CDS_SEC 1
J 0
(-5125 -775);
DISPLAY 0.680851 (-5125 -775);
DISPLAY INVISIBLE (-5125 -775);
FORCEPROP 1 LASTPIN (-5175 -875) $PN 1
J 0
(-5165 -895);
DISPLAY 0.489362 (-5165 -895);
PAINT MONO (-5165 -895);
FORCEPROP 1 LASTPIN (-5175 -1075) $PN 2
J 0
(-5165 -1095);
DISPLAY 0.489362 (-5165 -1095);
PAINT MONO (-5165 -1095);
FORCEPROP 1 LAST TOLERANCE 10%
J 0
(-5125 -975);
DISPLAY 0.489362 (-5125 -975);
PAINT SKYBLUE (-5125 -975);
FORCEPROP 1 LAST VOLTAGE 25V
J 0
(-5125 -925);
DISPLAY 0.489362 (-5125 -925);
PAINT SKYBLUE (-5125 -925);
FORCEPROP 1 LAST VALUE 0.1UF
J 0
(-5125 -875);
DISPLAY 0.489362 (-5125 -875);
PAINT SKYBLUE (-5125 -875);
FORCEPROP 1 LAST MATERIAL X7R
J 0
(-5125 -1025);
DISPLAY 0.489362 (-5125 -1025);
PAINT SKYBLUE (-5125 -1025);
FORCEPROP 1 LAST PACK_TYPE 0402
J 0
(-5125 -1075);
DISPLAY 0.489362 (-5125 -1075);
PAINT SKYBLUE (-5125 -1075);
FORCEPROP 2 LAST CDS_LIB pure_quanta
J 0
(-5175 -975);
DISPLAY INVISIBLE (-5175 -975);
FORCEPROP 1 LAST PATH I198
J 0
(-5125 -825);
DISPLAY 0.978723 (-5125 -825);
PAINT WHITE (-5125 -825);
DISPLAY INVISIBLE (-5125 -825);
FORCEPROP 1 LAST PART_NUMBER CH4104K1B00
J 0
(-5125 -1125);
DISPLAY 0.489362 (-5125 -1125);
PAINT SKYBLUE (-5125 -1125);
DISPLAY INVISIBLE (-5125 -1125);
FORCEADD UNIVERSAL_GND..1
(-5175 -1175);
FORCEPROP 3 LASTPIN (-5175 -1125) SIG_NAME GND\g
J 0
(-5165 -1115);
DISPLAY 0.659574 (-5165 -1115);
PAINT MONO (-5165 -1115);
DISPLAY INVISIBLE (-5165 -1115);
FORCEPROP 2 LAST CDS_LIB pure_quanta_power
J 0
(-5175 -1175);
DISPLAY INVISIBLE (-5175 -1175);
FORCEPROP 1 LAST PATH I199
J 0
(-5100 -1175);
DISPLAY 0.872340 (-5100 -1175);
PAINT AQUA (-5100 -1175);
DISPLAY INVISIBLE (-5100 -1175);
FORCEPROP 1 LAST HDL_POWER GND
J 1
(-5150 -1250);
DISPLAY 0.872340 (-5150 -1250);
PAINT GREEN (-5150 -1250);
DISPLAY INVISIBLE (-5150 -1250);
FORCEADD VCC_CORE..1
(-5250 -725);
FORCEPROP 3 LASTPIN (-5250 -775) SIG_NAME P3V3\g
J 0
(-5240 -765);
DISPLAY 0.659574 (-5240 -765);
PAINT MONO (-5240 -765);
DISPLAY INVISIBLE (-5240 -765);
FORCEPROP 1 LAST HDL_POWER P3V3
J 1
(-5250 -675);
DISPLAY 0.489362 (-5250 -675);
PAINT GREEN (-5250 -675);
FORCEPROP 2 LAST CDS_LIB pure_quanta_power
J 0
(-5250 -725);
DISPLAY INVISIBLE (-5250 -725);
FORCEPROP 1 LAST PATH I200
J 0
(-5200 -700);
DISPLAY 0.872340 (-5200 -700);
PAINT AQUA (-5200 -700);
DISPLAY INVISIBLE (-5200 -700);
FORCEADD VCC_CORE..1
(-1000 600);
FORCEPROP 3 LASTPIN (-1000 550) SIG_NAME P3V3\g
J 0
(-990 560);
DISPLAY 0.659574 (-990 560);
PAINT MONO (-990 560);
DISPLAY INVISIBLE (-990 560);
FORCEPROP 1 LAST HDL_POWER P3V3
J 1
(-1000 650);
DISPLAY 0.489362 (-1000 650);
PAINT GREEN (-1000 650);
FORCEPROP 2 LAST CDS_LIB pure_quanta_power
J 0
(-1000 600);
DISPLAY INVISIBLE (-1000 600);
FORCEPROP 1 LAST PATH I201
J 0
(-950 625);
DISPLAY 0.872340 (-950 625);
PAINT AQUA (-950 625);
DISPLAY INVISIBLE (-950 625);
FORCEADD Q_RES..2
(-1000 350);
FORCEPROP 1 LAST LOCATION R406
J 0
(-955 475);
DISPLAY 0.489362 (-955 475);
PAINT SKYBLUE (-955 475);
FORCEPROP 0 LAST $SEC 1
J 0
(-950 525);
DISPLAY 0.680851 (-950 525);
PAINT MONO (-950 525);
DISPLAY INVISIBLE (-950 525);
FORCEPROP 0 LAST CDS_SEC 1
J 0
(-950 525);
DISPLAY 1.021277 (-950 525);
DISPLAY INVISIBLE (-950 525);
FORCEPROP 1 LASTPIN (-1000 450) $PN 1
J 0
(-995 412);
DISPLAY 0.489362 (-995 412);
PAINT MONO (-995 412);
FORCEPROP 1 LASTPIN (-1000 250) $PN 2
J 0
(-995 260);
DISPLAY 0.489362 (-995 260);
PAINT MONO (-995 260);
FORCEPROP 1 LAST VALUE 4.7K
J 0
(-955 425);
DISPLAY 0.489362 (-955 425);
PAINT SKYBLUE (-955 425);
FORCEPROP 1 LAST TOLERANCE 5%
J 0
(-955 375);
DISPLAY 0.489362 (-955 375);
PAINT SKYBLUE (-955 375);
FORCEPROP 1 LAST WATTAGE 1/16W
J 0
(-960 325);
DISPLAY 0.489362 (-960 325);
PAINT SKYBLUE (-960 325);
FORCEPROP 1 LAST PACK_TYPE 0402LF
J 0
(-950 225);
DISPLAY 0.489362 (-950 225);
PAINT SKYBLUE (-950 225);
FORCEPROP 1 LAST MATERIAL EMPTY
J 0
(-960 275);
DISPLAY 0.489362 (-960 275);
PAINT RED (-960 275);
FORCEPROP 2 LAST CDS_LIB pure_quanta
J 0
(-1000 350);
DISPLAY INVISIBLE (-1000 350);
FORCEPROP 1 LAST PATH I202
J 0
(-950 525);
DISPLAY 0.978723 (-950 525);
PAINT WHITE (-950 525);
DISPLAY INVISIBLE (-950 525);
FORCEPROP 1 LAST PART_NUMBER TMP_QCS24702JB38
J 0
(-960 225);
DISPLAY 0.489362 (-960 225);
PAINT SKYBLUE (-960 225);
DISPLAY INVISIBLE (-960 225);
FORCEADD VCC_CORE..1
(-1275 600);
FORCEPROP 3 LASTPIN (-1275 550) SIG_NAME P3V3\g
J 0
(-1265 560);
DISPLAY 0.659574 (-1265 560);
PAINT MONO (-1265 560);
DISPLAY INVISIBLE (-1265 560);
FORCEPROP 1 LAST HDL_POWER P3V3
J 1
(-1275 650);
DISPLAY 0.489362 (-1275 650);
PAINT GREEN (-1275 650);
FORCEPROP 2 LAST CDS_LIB pure_quanta_power
J 0
(-1275 600);
DISPLAY INVISIBLE (-1275 600);
FORCEPROP 1 LAST PATH I203
J 0
(-1225 625);
DISPLAY 0.872340 (-1225 625);
PAINT AQUA (-1225 625);
DISPLAY INVISIBLE (-1225 625);
FORCEADD Q_RES..2
(-1275 350);
FORCEPROP 1 LAST LOCATION R368
J 0
(-1230 475);
DISPLAY 0.489362 (-1230 475);
PAINT SKYBLUE (-1230 475);
FORCEPROP 0 LAST $SEC 1
J 0
(-1225 525);
DISPLAY 0.680851 (-1225 525);
PAINT MONO (-1225 525);
DISPLAY INVISIBLE (-1225 525);
FORCEPROP 0 LAST CDS_SEC 1
J 0
(-1225 525);
DISPLAY 1.021277 (-1225 525);
DISPLAY INVISIBLE (-1225 525);
FORCEPROP 1 LASTPIN (-1275 450) $PN 1
J 0
(-1270 412);
DISPLAY 0.489362 (-1270 412);
PAINT MONO (-1270 412);
FORCEPROP 1 LASTPIN (-1275 250) $PN 2
J 0
(-1270 260);
DISPLAY 0.489362 (-1270 260);
PAINT MONO (-1270 260);
FORCEPROP 1 LAST PACK_TYPE 0402LF
J 0
(-1225 225);
DISPLAY 0.489362 (-1225 225);
PAINT SKYBLUE (-1225 225);
FORCEPROP 1 LAST TOLERANCE 5%
J 0
(-1230 375);
DISPLAY 0.489362 (-1230 375);
PAINT SKYBLUE (-1230 375);
FORCEPROP 1 LAST VALUE 4.7K
J 0
(-1230 425);
DISPLAY 0.489362 (-1230 425);
PAINT SKYBLUE (-1230 425);
FORCEPROP 1 LAST WATTAGE 1/16W
J 0
(-1235 325);
DISPLAY 0.489362 (-1235 325);
PAINT SKYBLUE (-1235 325);
FORCEPROP 1 LAST MATERIAL EMPTY
J 0
(-1235 275);
DISPLAY 0.489362 (-1235 275);
PAINT RED (-1235 275);
FORCEPROP 2 LAST CDS_LIB pure_quanta
J 0
(-1275 350);
DISPLAY INVISIBLE (-1275 350);
FORCEPROP 1 LAST PATH I204
J 0
(-1225 525);
DISPLAY 0.978723 (-1225 525);
PAINT WHITE (-1225 525);
DISPLAY INVISIBLE (-1225 525);
FORCEPROP 1 LAST PART_NUMBER TMP_QCS24702JB38
J 0
(-1235 225);
DISPLAY 0.489362 (-1235 225);
PAINT SKYBLUE (-1235 225);
DISPLAY INVISIBLE (-1235 225);
FORCEADD VCC_CORE..1
(-1575 600);
FORCEPROP 3 LASTPIN (-1575 550) SIG_NAME P3V3\g
J 0
(-1565 560);
DISPLAY 0.659574 (-1565 560);
PAINT MONO (-1565 560);
DISPLAY INVISIBLE (-1565 560);
FORCEPROP 1 LAST HDL_POWER P3V3
J 1
(-1575 650);
DISPLAY 0.489362 (-1575 650);
PAINT GREEN (-1575 650);
FORCEPROP 2 LAST CDS_LIB pure_quanta_power
J 0
(-1575 600);
DISPLAY INVISIBLE (-1575 600);
FORCEPROP 1 LAST PATH I205
J 0
(-1525 625);
DISPLAY 0.872340 (-1525 625);
PAINT AQUA (-1525 625);
DISPLAY INVISIBLE (-1525 625);
FORCEADD Q_RES..2
(-1575 350);
FORCEPROP 1 LAST LOCATION R365
J 0
(-1530 475);
DISPLAY 0.489362 (-1530 475);
PAINT SKYBLUE (-1530 475);
FORCEPROP 0 LAST $SEC 1
J 0
(-1525 525);
DISPLAY 0.680851 (-1525 525);
PAINT MONO (-1525 525);
DISPLAY INVISIBLE (-1525 525);
FORCEPROP 0 LAST CDS_SEC 1
J 0
(-1525 525);
DISPLAY 1.021277 (-1525 525);
DISPLAY INVISIBLE (-1525 525);
FORCEPROP 1 LASTPIN (-1575 450) $PN 1
J 0
(-1570 412);
DISPLAY 0.489362 (-1570 412);
PAINT MONO (-1570 412);
FORCEPROP 1 LASTPIN (-1575 250) $PN 2
J 0
(-1570 260);
DISPLAY 0.489362 (-1570 260);
PAINT MONO (-1570 260);
FORCEPROP 1 LAST MATERIAL EMPTY
J 0
(-1535 275);
DISPLAY 0.489362 (-1535 275);
PAINT RED (-1535 275);
FORCEPROP 1 LAST VALUE 4.7K
J 0
(-1530 425);
DISPLAY 0.489362 (-1530 425);
PAINT SKYBLUE (-1530 425);
FORCEPROP 1 LAST PACK_TYPE 0402LF
J 0
(-1525 225);
DISPLAY 0.489362 (-1525 225);
PAINT SKYBLUE (-1525 225);
FORCEPROP 1 LAST TOLERANCE 5%
J 0
(-1530 375);
DISPLAY 0.489362 (-1530 375);
PAINT SKYBLUE (-1530 375);
FORCEPROP 1 LAST WATTAGE 1/16W
J 0
(-1535 325);
DISPLAY 0.489362 (-1535 325);
PAINT SKYBLUE (-1535 325);
FORCEPROP 2 LAST CDS_LIB pure_quanta
J 0
(-1575 350);
DISPLAY INVISIBLE (-1575 350);
FORCEPROP 1 LAST PATH I206
J 0
(-1525 525);
DISPLAY 0.978723 (-1525 525);
PAINT WHITE (-1525 525);
DISPLAY INVISIBLE (-1525 525);
FORCEPROP 1 LAST PART_NUMBER TMP_QCS24702JB38
J 0
(-1535 225);
DISPLAY 0.489362 (-1535 225);
PAINT SKYBLUE (-1535 225);
DISPLAY INVISIBLE (-1535 225);
FORCEADD VCC_CORE..1
(-1900 600);
FORCEPROP 3 LASTPIN (-1900 550) SIG_NAME P3V3\g
J 0
(-1890 560);
DISPLAY 0.659574 (-1890 560);
PAINT MONO (-1890 560);
DISPLAY INVISIBLE (-1890 560);
FORCEPROP 1 LAST HDL_POWER P3V3
J 1
(-1900 650);
DISPLAY 0.489362 (-1900 650);
PAINT GREEN (-1900 650);
FORCEPROP 1 LAST PATH I207
J 0
(-1850 625);
DISPLAY 0.872340 (-1850 625);
PAINT AQUA (-1850 625);
DISPLAY INVISIBLE (-1850 625);
FORCEPROP 2 LAST CDS_LIB pure_quanta_power
J 0
(-1900 600);
DISPLAY INVISIBLE (-1900 600);
FORCEADD Q_RES..2
(-1900 350);
FORCEPROP 1 LAST LOCATION R361
J 0
(-1855 475);
DISPLAY 0.489362 (-1855 475);
PAINT SKYBLUE (-1855 475);
FORCEPROP 0 LAST $SEC 1
J 0
(-1850 525);
DISPLAY 0.680851 (-1850 525);
PAINT MONO (-1850 525);
DISPLAY INVISIBLE (-1850 525);
FORCEPROP 0 LAST CDS_SEC 1
J 0
(-1850 525);
DISPLAY 1.021277 (-1850 525);
DISPLAY INVISIBLE (-1850 525);
FORCEPROP 1 LASTPIN (-1900 450) $PN 1
J 0
(-1895 412);
DISPLAY 0.489362 (-1895 412);
PAINT MONO (-1895 412);
FORCEPROP 1 LASTPIN (-1900 250) $PN 2
J 0
(-1895 260);
DISPLAY 0.489362 (-1895 260);
PAINT MONO (-1895 260);
FORCEPROP 1 LAST TOLERANCE 5%
J 0
(-1855 375);
DISPLAY 0.489362 (-1855 375);
PAINT SKYBLUE (-1855 375);
FORCEPROP 1 LAST WATTAGE 1/16W
J 0
(-1860 325);
DISPLAY 0.489362 (-1860 325);
PAINT SKYBLUE (-1860 325);
FORCEPROP 1 LAST VALUE 4.7K
J 0
(-1855 425);
DISPLAY 0.489362 (-1855 425);
PAINT SKYBLUE (-1855 425);
FORCEPROP 1 LAST PACK_TYPE 0402LF
J 0
(-1850 225);
DISPLAY 0.489362 (-1850 225);
PAINT SKYBLUE (-1850 225);
FORCEPROP 1 LAST MATERIAL EMPTY
J 0
(-1860 275);
DISPLAY 0.489362 (-1860 275);
PAINT RED (-1860 275);
FORCEPROP 1 LAST PART_NUMBER TMP_QCS24702JB38
J 0
(-1860 225);
DISPLAY 0.489362 (-1860 225);
PAINT SKYBLUE (-1860 225);
DISPLAY INVISIBLE (-1860 225);
FORCEPROP 1 LAST PATH I208
J 0
(-1850 525);
DISPLAY 0.978723 (-1850 525);
PAINT WHITE (-1850 525);
DISPLAY INVISIBLE (-1850 525);
FORCEPROP 2 LAST CDS_LIB pure_quanta
J 0
(-1900 350);
DISPLAY INVISIBLE (-1900 350);
FORCEADD OFFPAGE..5
(-2825 50);
FORCEPROP 2 LAST $XR1 138 
J 0
(-3230 50);
DISPLAY 0.638298 (-3230 50);
PAINT MONO (-3230 50);
FORCEPROP 2 LAST $XR0 137 
J 0
(-3110 50);
DISPLAY 0.638298 (-3110 50);
PAINT MONO (-3110 50);
FORCEPROP 2 LAST CDS_LIB standard
J 0
(-2825 50);
DISPLAY INVISIBLE (-2825 50);
FORCEPROP 2 LAST PATH I209
J 0
(-2650 125);
DISPLAY 0.680851 (-2650 125);
DISPLAY INVISIBLE (-2650 125);
FORCEPROP 1 LAST OFFPAGE TRUE
J 0
(-2500 -75);
DISPLAY 0.872340 (-2500 -75);
PAINT GREEN (-2500 -75);
DISPLAY INVISIBLE (-2500 -75);
FORCEPROP 1 LAST COMMENT_BODY TRUE
J 0
(-2725 -25);
DISPLAY 0.872340 (-2725 -25);
PAINT GREEN (-2725 -25);
DISPLAY INVISIBLE (-2725 -25);
FORCEADD OFFPAGE..5
(-2825 0);
FORCEPROP 2 LAST $XR1 138 
J 0
(-3230 0);
DISPLAY 0.638298 (-3230 0);
PAINT MONO (-3230 0);
FORCEPROP 2 LAST $XR0 137 
J 0
(-3110 0);
DISPLAY 0.638298 (-3110 0);
PAINT MONO (-3110 0);
FORCEPROP 1 LAST COMMENT_BODY TRUE
J 0
(-2725 -75);
DISPLAY 0.872340 (-2725 -75);
PAINT GREEN (-2725 -75);
DISPLAY INVISIBLE (-2725 -75);
FORCEPROP 1 LAST OFFPAGE TRUE
J 0
(-2500 -125);
DISPLAY 0.872340 (-2500 -125);
PAINT GREEN (-2500 -125);
DISPLAY INVISIBLE (-2500 -125);
FORCEPROP 2 LAST PATH I210
J 0
(-2775 75);
DISPLAY 0.680851 (-2775 75);
DISPLAY INVISIBLE (-2775 75);
FORCEPROP 2 LAST CDS_LIB standard
J 0
(-2825 0);
DISPLAY INVISIBLE (-2825 0);
FORCEADD OFFPAGE..5
(-2825 -50);
FORCEPROP 2 LAST $XR1 138 
J 0
(-3230 -50);
DISPLAY 0.638298 (-3230 -50);
PAINT MONO (-3230 -50);
FORCEPROP 2 LAST $XR0 137 
J 0
(-3110 -50);
DISPLAY 0.638298 (-3110 -50);
PAINT MONO (-3110 -50);
FORCEPROP 1 LAST OFFPAGE TRUE
J 0
(-2500 -175);
DISPLAY 0.872340 (-2500 -175);
PAINT GREEN (-2500 -175);
DISPLAY INVISIBLE (-2500 -175);
FORCEPROP 1 LAST COMMENT_BODY TRUE
J 0
(-2725 -125);
DISPLAY 0.872340 (-2725 -125);
PAINT GREEN (-2725 -125);
DISPLAY INVISIBLE (-2725 -125);
FORCEPROP 2 LAST PATH I211
J 0
(-2775 25);
DISPLAY 0.680851 (-2775 25);
DISPLAY INVISIBLE (-2775 25);
FORCEPROP 2 LAST CDS_LIB standard
J 0
(-2825 -50);
DISPLAY INVISIBLE (-2825 -50);
FORCEADD OFFPAGE..5
(-2825 -100);
FORCEPROP 2 LAST $XR1 138 
J 0
(-3230 -100);
DISPLAY 0.638298 (-3230 -100);
PAINT MONO (-3230 -100);
FORCEPROP 2 LAST $XR0 137 
J 0
(-3110 -100);
DISPLAY 0.638298 (-3110 -100);
PAINT MONO (-3110 -100);
FORCEPROP 1 LAST OFFPAGE TRUE
J 0
(-2500 -225);
DISPLAY 0.872340 (-2500 -225);
PAINT GREEN (-2500 -225);
DISPLAY INVISIBLE (-2500 -225);
FORCEPROP 1 LAST COMMENT_BODY TRUE
J 0
(-2725 -175);
DISPLAY 0.872340 (-2725 -175);
PAINT GREEN (-2725 -175);
DISPLAY INVISIBLE (-2725 -175);
FORCEPROP 2 LAST PATH I212
J 0
(-2775 -25);
DISPLAY 0.680851 (-2775 -25);
DISPLAY INVISIBLE (-2775 -25);
FORCEPROP 2 LAST CDS_LIB standard
J 0
(-2825 -100);
DISPLAY INVISIBLE (-2825 -100);
FORCEADD PCA9617ADP..1
(-5900 1300);
FORCEPROP 1 LAST LOCATION U5
J 0
(-6174 1710);
DISPLAY 0.574468 (-6174 1710);
PAINT SKYBLUE (-6174 1710);
FORCEPROP 0 LAST $SEC 1
J 0
(-6150 1850);
DISPLAY 0.680851 (-6150 1850);
PAINT MONO (-6150 1850);
DISPLAY INVISIBLE (-6150 1850);
FORCEPROP 0 LAST CDS_SEC 1
J 0
(-6150 1850);
DISPLAY 0.680851 (-6150 1850);
DISPLAY INVISIBLE (-6150 1850);
FORCEPROP 0 LASTPIN (-5475 1100) $PN 5
J 0
(-5465 1110);
DISPLAY 0.680851 (-5465 1110);
PAINT MONO (-5465 1110);
FORCEPROP 0 LASTPIN (-6325 1100) $PN 4
J 2
(-6335 1110);
DISPLAY 0.680851 (-6335 1110);
PAINT MONO (-6335 1110);
FORCEPROP 0 LASTPIN (-6325 1350) $PN 2
J 2
(-6335 1360);
DISPLAY 0.680851 (-6335 1360);
PAINT MONO (-6335 1360);
FORCEPROP 0 LASTPIN (-5475 1350) $PN 7
J 0
(-5465 1360);
DISPLAY 0.680851 (-5465 1360);
PAINT MONO (-5465 1360);
FORCEPROP 0 LASTPIN (-6325 1250) $PN 3
J 2
(-6335 1260);
DISPLAY 0.680851 (-6335 1260);
PAINT MONO (-6335 1260);
FORCEPROP 0 LASTPIN (-5475 1250) $PN 6
J 0
(-5465 1260);
DISPLAY 0.680851 (-5465 1260);
PAINT MONO (-5465 1260);
FORCEPROP 0 LASTPIN (-6325 1500) $PN 1
J 2
(-6335 1510);
DISPLAY 0.680851 (-6335 1510);
PAINT MONO (-6335 1510);
FORCEPROP 0 LASTPIN (-5475 1500) $PN 8
J 0
(-5465 1510);
DISPLAY 0.680851 (-5465 1510);
PAINT MONO (-5465 1510);
FORCEPROP 1 LAST MATERIAL EMPTY
J 0
(-6174 1605);
DISPLAY 0.723404 (-6174 1605);
PAINT RED (-6174 1605);
FORCEPROP 1 LAST PART_NUMBER AL009617K02
J 0
(-6174 1660);
DISPLAY 0.468085 (-6174 1660);
PAINT SKYBLUE (-6174 1660);
FORCEPROP 2 LAST VALUE PCA9617ADP
J 0
(-6150 1750);
DISPLAY 0.553191 (-6150 1750);
PAINT SKYBLUE (-6150 1750);
FORCEPROP 2 LAST PART_TYPE SMLF
J 0
(-6150 1800);
DISPLAY 0.851064 (-6150 1800);
FORCEPROP 2 LAST CDS_LIB pure_quanta
J 0
(-5900 1300);
DISPLAY INVISIBLE (-5900 1300);
FORCEPROP 1 LAST PATH I213
J 0
(-5900 1300);
DISPLAY 0.723404 (-5900 1300);
PAINT GREEN (-5900 1300);
DISPLAY INVISIBLE (-5900 1300);
FORCEPROP 1 LAST NEEDS_NO_SIZE TRUE
J 0
(-5625 1000);
DISPLAY 0.468085 (-5625 1000);
PAINT GREEN (-5625 1000);
DISPLAY INVISIBLE (-5625 1000);
FORCEPROP 1 LAST CDS_LMAN_SYM_OUTLINE -275,300,275,-300
J 0
(-5900 1300);
DISPLAY 0.468085 (-5900 1300);
PAINT GREEN (-5900 1300);
DISPLAY INVISIBLE (-5900 1300);
FORCEADD PCA9617ADP..1
(-5825 -1425);
FORCEPROP 1 LAST $LOCATION U96
J 0
(-6099 -1015);
DISPLAY 0.574468 (-6099 -1015);
PAINT SKYBLUE (-6099 -1015);
FORCEPROP 0 LAST CDS_LOCATION U96
J 0
(-6075 -875);
DISPLAY 0.680851 (-6075 -875);
DISPLAY INVISIBLE (-6075 -875);
FORCEPROP 0 LAST $SEC 1
J 0
(-6075 -875);
DISPLAY 0.680851 (-6075 -875);
PAINT MONO (-6075 -875);
DISPLAY INVISIBLE (-6075 -875);
FORCEPROP 0 LAST CDS_SEC 1
J 0
(-6075 -875);
DISPLAY 0.680851 (-6075 -875);
DISPLAY INVISIBLE (-6075 -875);
FORCEPROP 0 LASTPIN (-5400 -1625) $PN 5
J 0
(-5390 -1615);
DISPLAY 0.680851 (-5390 -1615);
PAINT MONO (-5390 -1615);
FORCEPROP 0 LASTPIN (-6250 -1625) $PN 4
J 2
(-6260 -1615);
DISPLAY 0.680851 (-6260 -1615);
PAINT MONO (-6260 -1615);
FORCEPROP 0 LASTPIN (-6250 -1375) $PN 2
J 2
(-6260 -1365);
DISPLAY 0.680851 (-6260 -1365);
PAINT MONO (-6260 -1365);
FORCEPROP 0 LASTPIN (-5400 -1375) $PN 7
J 0
(-5390 -1365);
DISPLAY 0.680851 (-5390 -1365);
PAINT MONO (-5390 -1365);
FORCEPROP 0 LASTPIN (-6250 -1475) $PN 3
J 2
(-6260 -1465);
DISPLAY 0.680851 (-6260 -1465);
PAINT MONO (-6260 -1465);
FORCEPROP 0 LASTPIN (-5400 -1475) $PN 6
J 0
(-5390 -1465);
DISPLAY 0.680851 (-5390 -1465);
PAINT MONO (-5390 -1465);
FORCEPROP 0 LASTPIN (-6250 -1225) $PN 1
J 2
(-6260 -1215);
DISPLAY 0.680851 (-6260 -1215);
PAINT MONO (-6260 -1215);
FORCEPROP 0 LASTPIN (-5400 -1225) $PN 8
J 0
(-5390 -1215);
DISPLAY 0.680851 (-5390 -1215);
PAINT MONO (-5390 -1215);
FORCEPROP 1 LAST MATERIAL EMPTY
J 0
(-6099 -1120);
DISPLAY 0.723404 (-6099 -1120);
PAINT RED (-6099 -1120);
FORCEPROP 2 LAST PART_TYPE SMLF
J 0
(-6075 -925);
DISPLAY 0.851064 (-6075 -925);
FORCEPROP 2 LAST VALUE PCA9617ADP
J 0
(-6075 -975);
DISPLAY 0.553191 (-6075 -975);
PAINT SKYBLUE (-6075 -975);
FORCEPROP 1 LAST PART_NUMBER AL009617K02
J 0
(-6099 -1065);
DISPLAY 0.468085 (-6099 -1065);
PAINT SKYBLUE (-6099 -1065);
FORCEPROP 2 LAST CDS_LIB pure_quanta
J 0
(-5825 -1425);
DISPLAY INVISIBLE (-5825 -1425);
FORCEPROP 1 LAST PATH I214
J 0
(-5825 -1425);
DISPLAY 0.723404 (-5825 -1425);
PAINT GREEN (-5825 -1425);
DISPLAY INVISIBLE (-5825 -1425);
FORCEPROP 1 LAST NEEDS_NO_SIZE TRUE
J 0
(-5550 -1725);
DISPLAY 0.468085 (-5550 -1725);
PAINT GREEN (-5550 -1725);
DISPLAY INVISIBLE (-5550 -1725);
FORCEPROP 1 LAST CDS_LMAN_SYM_OUTLINE -275,300,275,-300
J 0
(-5825 -1425);
DISPLAY 0.468085 (-5825 -1425);
PAINT GREEN (-5825 -1425);
DISPLAY INVISIBLE (-5825 -1425);
FORCEADD UNIVERSAL_GND..1
(-6400 950);
FORCEPROP 3 LASTPIN (-6400 1000) SIG_NAME GND\g
J 0
(-6390 1010);
DISPLAY 0.659574 (-6390 1010);
PAINT MONO (-6390 1010);
DISPLAY INVISIBLE (-6390 1010);
FORCEPROP 2 LAST CDS_LIB pure_quanta_power
J 0
(-6400 950);
DISPLAY INVISIBLE (-6400 950);
FORCEPROP 1 LAST PATH I215
J 0
(-6325 950);
DISPLAY 0.872340 (-6325 950);
PAINT AQUA (-6325 950);
DISPLAY INVISIBLE (-6325 950);
FORCEPROP 1 LAST HDL_POWER GND
J 1
(-6375 875);
DISPLAY 0.872340 (-6375 875);
PAINT GREEN (-6375 875);
DISPLAY INVISIBLE (-6375 875);
FORCEADD UNIVERSAL_GND..1
(-6350 -1750);
FORCEPROP 3 LASTPIN (-6350 -1700) SIG_NAME GND\g
J 0
(-6340 -1690);
DISPLAY 0.659574 (-6340 -1690);
PAINT MONO (-6340 -1690);
DISPLAY INVISIBLE (-6340 -1690);
FORCEPROP 2 LAST CDS_LIB pure_quanta_power
J 0
(-6350 -1750);
DISPLAY INVISIBLE (-6350 -1750);
FORCEPROP 1 LAST PATH I216
J 0
(-6275 -1750);
DISPLAY 0.872340 (-6275 -1750);
PAINT AQUA (-6275 -1750);
DISPLAY INVISIBLE (-6275 -1750);
FORCEPROP 1 LAST HDL_POWER GND
J 1
(-6325 -1825);
DISPLAY 0.872340 (-6325 -1825);
PAINT GREEN (-6325 -1825);
DISPLAY INVISIBLE (-6325 -1825);
FORCEADD Q_RES..1
(-5900 2375);
FORCEPROP 1 LAST LOCATION R789
J 0
(-6125 2425);
DISPLAY 0.510638 (-6125 2425);
PAINT SKYBLUE (-6125 2425);
FORCEPROP 0 LAST $SEC 1
J 0
(-5675 2450);
DISPLAY 0.680851 (-5675 2450);
PAINT MONO (-5675 2450);
DISPLAY INVISIBLE (-5675 2450);
FORCEPROP 0 LAST CDS_SEC 1
J 0
(-5675 2450);
DISPLAY 0.680851 (-5675 2450);
DISPLAY INVISIBLE (-5675 2450);
FORCEPROP 1 LASTPIN (-6000 2375) $PN 1
J 0
(-5988 2387);
DISPLAY 0.787234 (-5988 2387);
PAINT MONO (-5988 2387);
FORCEPROP 1 LASTPIN (-5800 2375) $PN 2
J 0
(-5838 2387);
DISPLAY 0.787234 (-5838 2387);
PAINT MONO (-5838 2387);
FORCEPROP 1 LAST MATERIAL CHIP
J 0
(-6000 2425);
DISPLAY 0.510638 (-6000 2425);
PAINT SKYBLUE (-6000 2425);
FORCEPROP 1 LAST VALUE 0
J 2
(-5675 2425);
DISPLAY 0.404255 (-5675 2425);
PAINT SKYBLUE (-5675 2425);
FORCEPROP 1 LAST PACK_TYPE 0402LF
J 0
(-5950 2550);
DISPLAY 0.978723 (-5950 2550);
PAINT SKYBLUE (-5950 2550);
DISPLAY INVISIBLE (-5950 2550);
FORCEPROP 1 LAST PART_NUMBER CS00002JB38
J 0
(-5950 2475);
DISPLAY 0.978723 (-5950 2475);
PAINT SKYBLUE (-5950 2475);
DISPLAY INVISIBLE (-5950 2475);
FORCEPROP 1 LAST TOLERANCE 5%
J 0
(-5900 2275);
DISPLAY 0.978723 (-5900 2275);
DISPLAY INVISIBLE (-5900 2275);
FORCEPROP 1 LAST WATTAGE 1/16W
J 2
(-5975 2425);
DISPLAY 0.978723 (-5975 2425);
DISPLAY INVISIBLE (-5975 2425);
FORCEPROP 1 LAST PATH I217
J 0
(-5950 2525);
DISPLAY 0.978723 (-5950 2525);
PAINT WHITE (-5950 2525);
DISPLAY INVISIBLE (-5950 2525);
FORCEPROP 2 LAST CDS_LIB pure_quanta
J 0
(-5900 2375);
DISPLAY INVISIBLE (-5900 2375);
FORCEADD Q_RES..1
(-5900 2325);
FORCEPROP 1 LAST LOCATION R790
J 0
(-6125 2275);
DISPLAY 0.510638 (-6125 2275);
PAINT SKYBLUE (-6125 2275);
FORCEPROP 0 LAST $SEC 1
J 0
(-5675 2300);
DISPLAY 0.680851 (-5675 2300);
PAINT MONO (-5675 2300);
DISPLAY INVISIBLE (-5675 2300);
FORCEPROP 0 LAST CDS_SEC 1
J 0
(-5675 2300);
DISPLAY 0.680851 (-5675 2300);
DISPLAY INVISIBLE (-5675 2300);
FORCEPROP 1 LASTPIN (-6000 2325) $PN 1
J 0
(-5988 2337);
DISPLAY 0.787234 (-5988 2337);
PAINT MONO (-5988 2337);
FORCEPROP 1 LASTPIN (-5800 2325) $PN 2
J 0
(-5838 2337);
DISPLAY 0.787234 (-5838 2337);
PAINT MONO (-5838 2337);
FORCEPROP 1 LAST MATERIAL CHIP
J 0
(-6000 2250);
DISPLAY 0.510638 (-6000 2250);
PAINT SKYBLUE (-6000 2250);
FORCEPROP 1 LAST VALUE 0
J 2
(-5675 2275);
DISPLAY 0.404255 (-5675 2275);
PAINT SKYBLUE (-5675 2275);
FORCEPROP 2 LAST CDS_LIB pure_quanta
J 0
(-5900 2325);
DISPLAY INVISIBLE (-5900 2325);
FORCEPROP 1 LAST PATH I218
J 0
(-5950 2475);
DISPLAY 0.978723 (-5950 2475);
PAINT WHITE (-5950 2475);
DISPLAY INVISIBLE (-5950 2475);
FORCEPROP 1 LAST WATTAGE 1/16W
J 2
(-5975 2375);
DISPLAY 0.978723 (-5975 2375);
DISPLAY INVISIBLE (-5975 2375);
FORCEPROP 1 LAST TOLERANCE 5%
J 0
(-5900 2225);
DISPLAY 0.978723 (-5900 2225);
DISPLAY INVISIBLE (-5900 2225);
FORCEPROP 1 LAST PART_NUMBER CS00002JB38
J 0
(-5950 2425);
DISPLAY 0.978723 (-5950 2425);
PAINT SKYBLUE (-5950 2425);
DISPLAY INVISIBLE (-5950 2425);
FORCEPROP 1 LAST PACK_TYPE 0402LF
J 0
(-5950 2500);
DISPLAY 0.978723 (-5950 2500);
PAINT SKYBLUE (-5950 2500);
DISPLAY INVISIBLE (-5950 2500);
FORCEADD Q_RES..1
(-5825 -300);
FORCEPROP 1 LAST LOCATION R791
J 0
(-6050 -250);
DISPLAY 0.510638 (-6050 -250);
PAINT SKYBLUE (-6050 -250);
FORCEPROP 0 LAST $SEC 1
J 0
(-5600 -225);
DISPLAY 0.680851 (-5600 -225);
PAINT MONO (-5600 -225);
DISPLAY INVISIBLE (-5600 -225);
FORCEPROP 0 LAST CDS_SEC 1
J 0
(-5600 -225);
DISPLAY 0.680851 (-5600 -225);
DISPLAY INVISIBLE (-5600 -225);
FORCEPROP 1 LASTPIN (-5925 -300) $PN 1
J 0
(-5913 -288);
DISPLAY 0.787234 (-5913 -288);
PAINT MONO (-5913 -288);
FORCEPROP 1 LASTPIN (-5725 -300) $PN 2
J 0
(-5763 -288);
DISPLAY 0.787234 (-5763 -288);
PAINT MONO (-5763 -288);
FORCEPROP 1 LAST MATERIAL CHIP
J 0
(-5925 -250);
DISPLAY 0.510638 (-5925 -250);
PAINT SKYBLUE (-5925 -250);
FORCEPROP 1 LAST VALUE 0
J 2
(-5600 -250);
DISPLAY 0.404255 (-5600 -250);
PAINT SKYBLUE (-5600 -250);
FORCEPROP 2 LAST CDS_LIB pure_quanta
J 0
(-5825 -300);
DISPLAY INVISIBLE (-5825 -300);
FORCEPROP 1 LAST PATH I219
J 0
(-5875 -150);
DISPLAY 0.978723 (-5875 -150);
PAINT WHITE (-5875 -150);
DISPLAY INVISIBLE (-5875 -150);
FORCEPROP 1 LAST WATTAGE 1/16W
J 2
(-5900 -250);
DISPLAY 0.978723 (-5900 -250);
DISPLAY INVISIBLE (-5900 -250);
FORCEPROP 1 LAST TOLERANCE 5%
J 0
(-5825 -400);
DISPLAY 0.978723 (-5825 -400);
DISPLAY INVISIBLE (-5825 -400);
FORCEPROP 1 LAST PART_NUMBER CS00002JB38
J 0
(-5875 -200);
DISPLAY 0.978723 (-5875 -200);
PAINT SKYBLUE (-5875 -200);
DISPLAY INVISIBLE (-5875 -200);
FORCEPROP 1 LAST PACK_TYPE 0402LF
J 0
(-5875 -125);
DISPLAY 0.978723 (-5875 -125);
PAINT SKYBLUE (-5875 -125);
DISPLAY INVISIBLE (-5875 -125);
FORCEADD Q_RES..1
(-5825 -350);
FORCEPROP 1 LAST LOCATION R792
J 0
(-6050 -400);
DISPLAY 0.510638 (-6050 -400);
PAINT SKYBLUE (-6050 -400);
FORCEPROP 0 LAST $SEC 1
J 0
(-5600 -375);
DISPLAY 0.680851 (-5600 -375);
PAINT MONO (-5600 -375);
DISPLAY INVISIBLE (-5600 -375);
FORCEPROP 0 LAST CDS_SEC 1
J 0
(-5600 -375);
DISPLAY 0.680851 (-5600 -375);
DISPLAY INVISIBLE (-5600 -375);
FORCEPROP 1 LASTPIN (-5925 -350) $PN 1
J 0
(-5913 -338);
DISPLAY 0.787234 (-5913 -338);
PAINT MONO (-5913 -338);
FORCEPROP 1 LASTPIN (-5725 -350) $PN 2
J 0
(-5763 -338);
DISPLAY 0.787234 (-5763 -338);
PAINT MONO (-5763 -338);
FORCEPROP 1 LAST MATERIAL CHIP
J 0
(-5925 -400);
DISPLAY 0.510638 (-5925 -400);
PAINT SKYBLUE (-5925 -400);
FORCEPROP 1 LAST VALUE 0
J 2
(-5600 -400);
DISPLAY 0.404255 (-5600 -400);
PAINT SKYBLUE (-5600 -400);
FORCEPROP 2 LAST CDS_LIB pure_quanta
J 0
(-5825 -350);
DISPLAY INVISIBLE (-5825 -350);
FORCEPROP 1 LAST PATH I220
J 0
(-5875 -200);
DISPLAY 0.978723 (-5875 -200);
PAINT WHITE (-5875 -200);
DISPLAY INVISIBLE (-5875 -200);
FORCEPROP 1 LAST WATTAGE 1/16W
J 2
(-5900 -300);
DISPLAY 0.978723 (-5900 -300);
DISPLAY INVISIBLE (-5900 -300);
FORCEPROP 1 LAST TOLERANCE 5%
J 0
(-5825 -450);
DISPLAY 0.978723 (-5825 -450);
DISPLAY INVISIBLE (-5825 -450);
FORCEPROP 1 LAST PART_NUMBER CS00002JB38
J 0
(-5875 -250);
DISPLAY 0.978723 (-5875 -250);
PAINT SKYBLUE (-5875 -250);
DISPLAY INVISIBLE (-5875 -250);
FORCEPROP 1 LAST PACK_TYPE 0402LF
J 0
(-5875 -175);
DISPLAY 0.978723 (-5875 -175);
PAINT SKYBLUE (-5875 -175);
DISPLAY INVISIBLE (-5875 -175);
FORCEADD Q_RES..2
(-4150 775);
FORCEPROP 1 LAST $LOCATION R78
J 0
(-4105 900);
DISPLAY 0.489362 (-4105 900);
PAINT SKYBLUE (-4105 900);
FORCEPROP 0 LAST CDS_LOCATION R78
J 0
(-4100 925);
DISPLAY 0.680851 (-4100 925);
DISPLAY INVISIBLE (-4100 925);
FORCEPROP 0 LAST $SEC 1
J 0
(-4100 925);
DISPLAY 0.680851 (-4100 925);
PAINT MONO (-4100 925);
DISPLAY INVISIBLE (-4100 925);
FORCEPROP 0 LAST CDS_SEC 1
J 0
(-4100 925);
DISPLAY 0.680851 (-4100 925);
DISPLAY INVISIBLE (-4100 925);
FORCEPROP 1 LASTPIN (-4150 875) $PN 1
J 0
(-4145 837);
DISPLAY 0.787234 (-4145 837);
PAINT MONO (-4145 837);
FORCEPROP 1 LASTPIN (-4150 675) $PN 2
J 0
(-4145 685);
DISPLAY 0.787234 (-4145 685);
PAINT MONO (-4145 685);
FORCEPROP 1 LAST WATTAGE 1/16W
J 0
(-4110 750);
DISPLAY 0.489362 (-4110 750);
PAINT SKYBLUE (-4110 750);
FORCEPROP 1 LAST TOLERANCE 5%
J 0
(-4105 800);
DISPLAY 0.489362 (-4105 800);
PAINT SKYBLUE (-4105 800);
FORCEPROP 1 LAST MATERIAL EMPTY
J 0
(-4110 700);
DISPLAY 0.489362 (-4110 700);
PAINT RED (-4110 700);
FORCEPROP 1 LAST PACK_TYPE 0402LF
J 0
(-4100 650);
DISPLAY 0.489362 (-4100 650);
PAINT SKYBLUE (-4100 650);
FORCEPROP 1 LAST VALUE 4.7K
J 0
(-4105 850);
DISPLAY 0.489362 (-4105 850);
PAINT SKYBLUE (-4105 850);
FORCEPROP 1 LAST PART_NUMBER TMP_QCS24702JB38
J 0
(-4110 650);
DISPLAY 0.489362 (-4110 650);
PAINT SKYBLUE (-4110 650);
DISPLAY INVISIBLE (-4110 650);
FORCEPROP 1 LAST PATH I221
J 0
(-4100 950);
DISPLAY 0.978723 (-4100 950);
PAINT WHITE (-4100 950);
DISPLAY INVISIBLE (-4100 950);
FORCEPROP 2 LAST CDS_LIB pure_quanta
J 0
(-4150 775);
DISPLAY INVISIBLE (-4150 775);
FORCEADD VCC_CORE..1
(-4150 1050);
FORCEPROP 3 LASTPIN (-4150 1000) SIG_NAME P3V3\g
J 0
(-4140 1010);
DISPLAY 0.659574 (-4140 1010);
PAINT MONO (-4140 1010);
DISPLAY INVISIBLE (-4140 1010);
FORCEPROP 1 LAST HDL_POWER P3V3
J 1
(-4150 1100);
DISPLAY 0.489362 (-4150 1100);
PAINT GREEN (-4150 1100);
FORCEPROP 1 LAST PATH I222
J 0
(-4100 1075);
DISPLAY 0.872340 (-4100 1075);
PAINT AQUA (-4100 1075);
DISPLAY INVISIBLE (-4100 1075);
FORCEPROP 2 LAST CDS_LIB pure_quanta_power
J 0
(-4150 1050);
DISPLAY INVISIBLE (-4150 1050);
FORCEADD VCC_CORE..1
(-4025 -1700);
FORCEPROP 3 LASTPIN (-4025 -1750) SIG_NAME P3V3\g
J 0
(-4015 -1740);
DISPLAY 0.659574 (-4015 -1740);
PAINT MONO (-4015 -1740);
DISPLAY INVISIBLE (-4015 -1740);
FORCEPROP 1 LAST HDL_POWER P3V3
J 1
(-4025 -1650);
DISPLAY 0.489362 (-4025 -1650);
PAINT GREEN (-4025 -1650);
FORCEPROP 2 LAST CDS_LIB pure_quanta_power
J 0
(-4025 -1700);
DISPLAY INVISIBLE (-4025 -1700);
FORCEPROP 1 LAST PATH I223
J 0
(-3975 -1675);
DISPLAY 0.872340 (-3975 -1675);
PAINT AQUA (-3975 -1675);
DISPLAY INVISIBLE (-3975 -1675);
FORCEADD Q_RES..2
(-4025 -1975);
FORCEPROP 1 LAST $LOCATION R200
J 0
(-3980 -1850);
DISPLAY 0.638298 (-3980 -1850);
PAINT SKYBLUE (-3980 -1850);
FORCEPROP 0 LAST CDS_LOCATION R200
J 0
(-3975 -1800);
DISPLAY 0.680851 (-3975 -1800);
DISPLAY INVISIBLE (-3975 -1800);
FORCEPROP 0 LAST $SEC 1
J 0
(-3975 -1800);
DISPLAY 0.680851 (-3975 -1800);
PAINT MONO (-3975 -1800);
DISPLAY INVISIBLE (-3975 -1800);
FORCEPROP 0 LAST CDS_SEC 1
J 0
(-3975 -1800);
DISPLAY 0.680851 (-3975 -1800);
DISPLAY INVISIBLE (-3975 -1800);
FORCEPROP 1 LASTPIN (-4025 -1875) $PN 1
J 0
(-4020 -1913);
DISPLAY 0.787234 (-4020 -1913);
PAINT MONO (-4020 -1913);
FORCEPROP 1 LASTPIN (-4025 -2075) $PN 2
J 0
(-4020 -2065);
DISPLAY 0.787234 (-4020 -2065);
PAINT MONO (-4020 -2065);
FORCEPROP 1 LAST PACK_TYPE 0402LF
J 0
(-3975 -2100);
DISPLAY 0.489362 (-3975 -2100);
PAINT SKYBLUE (-3975 -2100);
FORCEPROP 1 LAST WATTAGE 1/16W
J 0
(-3985 -2000);
DISPLAY 0.489362 (-3985 -2000);
PAINT SKYBLUE (-3985 -2000);
FORCEPROP 1 LAST MATERIAL EMPTY
J 0
(-3985 -2050);
DISPLAY 0.489362 (-3985 -2050);
PAINT RED (-3985 -2050);
FORCEPROP 1 LAST TOLERANCE 5%
J 0
(-3980 -1950);
DISPLAY 0.489362 (-3980 -1950);
PAINT SKYBLUE (-3980 -1950);
FORCEPROP 1 LAST VALUE 4.7K
J 0
(-3980 -1900);
DISPLAY 0.489362 (-3980 -1900);
PAINT SKYBLUE (-3980 -1900);
FORCEPROP 2 LAST CDS_LIB pure_quanta
J 0
(-4025 -1975);
DISPLAY INVISIBLE (-4025 -1975);
FORCEPROP 1 LAST PATH I224
J 0
(-3975 -1800);
DISPLAY 0.978723 (-3975 -1800);
PAINT WHITE (-3975 -1800);
DISPLAY INVISIBLE (-3975 -1800);
FORCEPROP 1 LAST PART_NUMBER TMP_QCS24702JB38
J 0
(-3985 -2100);
DISPLAY 0.489362 (-3985 -2100);
PAINT SKYBLUE (-3985 -2100);
DISPLAY INVISIBLE (-3985 -2100);
FORCEADD DNS..2
(-1850 325);
PAINT RED (-1850 325);
FORCEPROP 1 LAST COMMENT_BODY TRUE
J 0
(-1850 325);
PAINT RED (-1850 325);
DISPLAY INVISIBLE (-1850 325);
FORCEPROP 2 LAST CDS_LIB mstr_misc
J 0
(-1850 325);
DISPLAY INVISIBLE (-1850 325);
FORCEADD QUANTA_TITLE_BLOCK_C..1
(-50 -3000);
FORCEPROP 0 LAST CDS_CON_LAST_MODIFIED Fri Mar 11 14:53:13 2022
J 0
(-1935 -2985);
DISPLAY INVISIBLE (-1935 -2985);
FORCEPROP 1 LAST CUSTOM_TXT_CDS <CON_LAST_MODIFIED>
J 0
(-1935 -2985);
DISPLAY 0.978723 (-1935 -2985);
FORCEPROP 2 LAST CUSTOM_TXT_CDS <XR_PAGE_TITLE>
J 0
(-7940 2250);
DISPLAY 0.638298 (-7940 2250);
PAINT PINK (-7940 2250);
DISPLAY INVISIBLE (-7940 2250);
FORCEPROP 1 LAST CUSTOM_TXT_CDS <NAME_2>
J 0
(-3225 -2950);
FORCEPROP 1 LAST CUSTOM_TXT_CDS <NAME_1>
J 0
(-3225 -2825);
FORCEPROP 1 LAST CUSTOM_TXT_CDS <Q_NUMBER>
J 0
(-1453 -2897);
DISPLAY 1.212766 (-1453 -2897);
FORCEPROP 1 LAST CUSTOM_TXT_CDS <Q_PROJ>
J 0
(-2432 -2898);
DISPLAY 1.212766 (-2432 -2898);
FORCEPROP 1 LAST CUSTOM_TXT_CDS <Q_REV>
J 0
(-234 -2897);
DISPLAY 1.212766 (-234 -2897);
FORCEPROP 1 LAST CUSTOM_TXT_CDS <CON_PAGE_NUM> OF <CON_TOTAL_PAGES>
J 0
(-496 -2982);
DISPLAY 0.978723 (-496 -2982);
FORCEPROP 1 LAST Q_DEPT BU9
J 1
(-3813 -2951);
DISPLAY 1.957447 (-3813 -2951);
PAINT GREEN (-3813 -2951);
FORCEPROP 1 LAST Q_TITLE I2C MUX - APML(1/2)
J 0
(-9350 -2950);
DISPLAY 2.446809 (-9350 -2950);
PAINT GREEN (-9350 -2950);
FORCEPROP 2 LAST CDS_LIB pure_quanta
J 0
(-50 -3000);
DISPLAY INVISIBLE (-50 -3000);
FORCEPROP 1 LAST CDS_LMAN_SYM_OUTLINE -9475,6775,100,-125
J 0
(-50 -3000);
DISPLAY 0.468085 (-50 -3000);
PAINT GREEN (-50 -3000);
DISPLAY INVISIBLE (-50 -3000);
FORCEPROP 2 LAST PAGE_BORDER TRUE
J 0
(-7940 2250);
DISPLAY 0.638298 (-7940 2250);
PAINT PINK (-7940 2250);
DISPLAY INVISIBLE (-7940 2250);
FORCEPROP 1 LAST COMMENT_BODY TRUE
J 0
(-38 -3013);
DISPLAY 0.978723 (-38 -3013);
PAINT GREEN (-38 -3013);
DISPLAY INVISIBLE (-38 -3013);
FORCEPROP 2 LAST CDS_XR_PAGE_TITLE CR-137 : @T6G_MB_LIB.T6G(SCH_1):PAGE137
J 0
(-7940 2250);
DISPLAY 0.638298 (-7940 2250);
PAINT PINK (-7940 2250);
DISPLAY INVISIBLE (-7940 2250);
FORCEADD DNS..2
(-4000 -1975);
PAINT RED (-4000 -1975);
FORCEPROP 2 LAST CDS_LIB mstr_misc
J 0
(-4000 -1975);
DISPLAY INVISIBLE (-4000 -1975);
FORCEPROP 1 LAST COMMENT_BODY TRUE
J 0
(-4000 -1975);
PAINT RED (-4000 -1975);
DISPLAY INVISIBLE (-4000 -1975);
FORCEADD DNS..2
(-4125 775);
PAINT RED (-4125 775);
FORCEPROP 1 LAST COMMENT_BODY TRUE
J 0
(-4125 775);
PAINT RED (-4125 775);
DISPLAY INVISIBLE (-4125 775);
FORCEPROP 2 LAST CDS_LIB mstr_misc
J 0
(-4125 775);
DISPLAY INVISIBLE (-4125 775);
FORCEADD DNS..2
(-1550 325);
PAINT RED (-1550 325);
FORCEPROP 2 LAST CDS_LIB mstr_misc
J 0
(-1550 325);
DISPLAY INVISIBLE (-1550 325);
FORCEPROP 1 LAST COMMENT_BODY TRUE
J 0
(-1550 325);
PAINT RED (-1550 325);
DISPLAY INVISIBLE (-1550 325);
FORCEADD DNS..2
(-1250 325);
PAINT RED (-1250 325);
FORCEPROP 2 LAST CDS_LIB mstr_misc
J 0
(-1250 325);
DISPLAY INVISIBLE (-1250 325);
FORCEPROP 1 LAST COMMENT_BODY TRUE
J 0
(-1250 325);
PAINT RED (-1250 325);
DISPLAY INVISIBLE (-1250 325);
FORCEADD DNS..2
(-975 325);
PAINT RED (-975 325);
FORCEPROP 2 LAST CDS_LIB mstr_misc
J 0
(-975 325);
DISPLAY INVISIBLE (-975 325);
FORCEPROP 1 LAST COMMENT_BODY TRUE
J 0
(-975 325);
PAINT RED (-975 325);
DISPLAY INVISIBLE (-975 325);
FORCEADD DNS..2
(-5950 1325);
PAINT RED (-5950 1325);
FORCEPROP 2 LAST CDS_LIB mstr_misc
J 0
(-5950 1325);
DISPLAY INVISIBLE (-5950 1325);
FORCEPROP 1 LAST COMMENT_BODY TRUE
J 0
(-5950 1325);
PAINT RED (-5950 1325);
DISPLAY INVISIBLE (-5950 1325);
FORCEADD DNS..2
(-5875 -1400);
PAINT RED (-5875 -1400);
FORCEPROP 2 LAST CDS_LIB mstr_misc
J 0
(-5875 -1400);
DISPLAY INVISIBLE (-5875 -1400);
FORCEPROP 1 LAST COMMENT_BODY TRUE
J 0
(-5875 -1400);
PAINT RED (-5875 -1400);
DISPLAY INVISIBLE (-5875 -1400);
WIRE 16 -1 (-6575 1650)(-6575 1600);
WIRE 16 -1 (-5250 1650)(-5250 1600);
WIRE 16 -1 (-6500 -1075)(-6500 -1125);
WIRE 16 -1 (-5175 -1075)(-5175 -1125);
WIRE 16 -1 (-1000 550)(-1000 450);
WIRE 16 -1 (-1275 550)(-1275 450);
WIRE 16 -1 (-1575 550)(-1575 450);
WIRE 16 -1 (-1900 550)(-1900 450);
WIRE 16 -1 (-6325 1100)(-6400 1100);
WIRE 16 -1 (-6400 1100)(-6400 1000);
WIRE 16 -1 (-6350 -1625)(-6350 -1700);
WIRE 16 -1 (-6250 -1625)(-6350 -1625);
WIRE 16 -1 (-4150 875)(-4150 1000);
WIRE 16 -1 (-4025 -1875)(-4025 -1750);
WIRE 16 -1 (-7850 1250)(-7150 1250);
FORCEPROP 2 LAST SIG_NAME SMB_SCM_10_R_SDA
J 0
(-7800 1260);
DISPLAY 0.489362 (-7800 1260);
WIRE 16 -1 (-7150 1250)(-7150 2325);
WIRE 16 -1 (-7150 1250)(-6325 1250);
WIRE 16 -1 (-6000 2325)(-7150 2325);
WIRE 16 -1 (-5800 2375)(-4325 2375);
WIRE 16 -1 (-4325 1350)(-4325 2375);
WIRE 16 -1 (-4325 1350)(-4125 1350);
WIRE 16 -1 (-5475 1350)(-4325 1350);
FORCEPROP 2 LAST SIG_NAME SMB_SCM_10_XLTR_R_SCL
J 0
(-5175 1360);
DISPLAY 0.489362 (-5175 1360);
FORCEPROP 2 LASTPROP $XRERR UNIQUE?
J 0
(-5415 1360);
DISPLAY 0.638298 (-5415 1360);
PAINT MONO (-5415 1360);
DISPLAY INVISIBLE (-5415 1360);
WIRE 16 -1 (-6000 2375)(-7225 2375);
WIRE 16 -1 (-7225 1350)(-7225 2375);
WIRE 16 -1 (-7225 1350)(-6325 1350);
WIRE 16 -1 (-7900 1350)(-7225 1350);
FORCEPROP 2 LAST SIG_NAME SMB_SCM_10_R_SCL
J 0
(-7800 1360);
DISPLAY 0.489362 (-7800 1360);
WIRE 16 -1 (-1275 250)(-1275 -50);
WIRE 16 -1 (-2775 -50)(-1275 -50);
FORCEPROP 2 LAST SIG_NAME SMB_SCM_11_XLTR_SCL
J 0
(-2625 -40);
DISPLAY 0.489362 (-2625 -40);
WIRE 16 -1 (-1575 250)(-1575 0);
WIRE 16 -1 (-2775 0)(-1575 0);
FORCEPROP 2 LAST SIG_NAME SMB_SCM_10_XLTR_SDA
J 0
(-2625 10);
DISPLAY 0.489362 (-2625 10);
WIRE 16 -1 (-3850 -1375)(-3100 -1375);
FORCEPROP 2 LAST SIG_NAME SMB_SCM_11_XLTR_SCL
J 2
(-3210 -1365);
DISPLAY 0.489362 (-3210 -1365);
WIRE 16 -1 (-4025 -2150)(-4025 -2075);
WIRE 16 -1 (-4025 -2150)(-4725 -2150);
WIRE 16 -1 (-4725 -1625)(-4725 -2150);
WIRE 16 -1 (-5400 -1625)(-4725 -1625);
FORCEPROP 2 LAST SIG_NAME PU_U96_EN
J 0
(-5235 -1615);
DISPLAY 0.489362 (-5235 -1615);
FORCEPROP 2 LASTPROP $XRERR UNIQUE?
J 0
(-5475 -1615);
DISPLAY 0.638298 (-5475 -1615);
PAINT MONO (-5475 -1615);
DISPLAY INVISIBLE (-5475 -1615);
WIRE 16 -1 (-5925 -300)(-6975 -300);
WIRE 16 -1 (-6975 -1375)(-6975 -300);
WIRE 16 -1 (-6975 -1375)(-6250 -1375);
WIRE 16 -1 (-7775 -1375)(-6975 -1375);
FORCEPROP 2 LAST SIG_NAME SMB_SCM_11_R_SCL
J 0
(-7675 -1365);
DISPLAY 0.489362 (-7675 -1365);
WIRE 16 -1 (-7725 -1475)(-6900 -1475);
FORCEPROP 2 LAST SIG_NAME SMB_SCM_11_R_SDA
J 0
(-7675 -1465);
DISPLAY 0.489362 (-7675 -1465);
WIRE 16 -1 (-6900 -1475)(-6900 -350);
WIRE 16 -1 (-6900 -1475)(-6250 -1475);
WIRE 16 -1 (-5925 -350)(-6900 -350);
WIRE 16 -1 (-5400 -1225)(-5250 -1225);
WIRE 16 -1 (-5250 -875)(-5250 -1225);
WIRE 16 -1 (-5175 -875)(-5250 -875);
WIRE 16 -1 (-5250 -775)(-5250 -875);
WIRE 16 -1 (-6500 -875)(-6500 -800);
WIRE 16 -1 (-6500 -800)(-6325 -800);
WIRE 16 -1 (-6325 -750)(-6325 -800);
WIRE 16 -1 (-6325 -1225)(-6325 -800);
WIRE 16 -1 (-6250 -1225)(-6325 -1225);
WIRE 16 -1 (-5475 1500)(-5325 1500);
WIRE 16 -1 (-5325 1850)(-5325 1500);
WIRE 16 -1 (-5325 1950)(-5325 1850);
WIRE 16 -1 (-5250 1850)(-5325 1850);
WIRE 16 -1 (-6575 1850)(-6575 1925);
WIRE 16 -1 (-6575 1925)(-6400 1925);
WIRE 16 -1 (-6400 1975)(-6400 1925);
WIRE 16 -1 (-6400 1500)(-6400 1925);
WIRE 16 -1 (-6325 1500)(-6400 1500);
WIRE 16 -1 (-3925 1350)(-3200 1350);
FORCEPROP 2 LAST SIG_NAME SMB_SCM_10_XLTR_SCL
J 2
(-3310 1360);
DISPLAY 0.489362 (-3310 1360);
WIRE 16 -1 (-5800 2325)(-4350 2325);
WIRE 16 -1 (-4350 1250)(-4350 2325);
WIRE 16 -1 (-4350 1250)(-4125 1250);
WIRE 16 -1 (-5475 1250)(-4350 1250);
FORCEPROP 2 LAST SIG_NAME SMB_SCM_10_XLTR_R_SDA
J 0
(-5175 1260);
DISPLAY 0.489362 (-5175 1260);
FORCEPROP 2 LASTPROP $XRERR UNIQUE?
J 0
(-5415 1260);
DISPLAY 0.638298 (-5415 1260);
PAINT MONO (-5415 1260);
DISPLAY INVISIBLE (-5415 1260);
WIRE 16 -1 (-5725 -350)(-4400 -350);
WIRE 16 -1 (-4400 -1475)(-4400 -350);
WIRE 16 -1 (-4400 -1475)(-4050 -1475);
WIRE 16 -1 (-5400 -1475)(-4400 -1475);
FORCEPROP 2 LAST SIG_NAME SMB_SCM_11_XLTR_R_SDA
J 0
(-5075 -1465);
DISPLAY 0.489362 (-5075 -1465);
FORCEPROP 2 LASTPROP $XRERR UNIQUE?
J 0
(-5315 -1465);
DISPLAY 0.638298 (-5315 -1465);
PAINT MONO (-5315 -1465);
DISPLAY INVISIBLE (-5315 -1465);
WIRE 16 -1 (-5725 -300)(-4350 -300);
WIRE 16 -1 (-4350 -300)(-4350 -1375);
WIRE 16 -1 (-4350 -1375)(-4050 -1375);
WIRE 16 -1 (-5400 -1375)(-4350 -1375);
FORCEPROP 2 LAST SIG_NAME SMB_SCM_11_XLTR_R_SCL
J 0
(-5075 -1365);
DISPLAY 0.489362 (-5075 -1365);
FORCEPROP 2 LASTPROP $XRERR UNIQUE?
J 0
(-5315 -1365);
DISPLAY 0.638298 (-5315 -1365);
PAINT MONO (-5315 -1365);
DISPLAY INVISIBLE (-5315 -1365);
WIRE 16 -1 (-1000 250)(-1000 -100);
WIRE 16 -1 (-2775 -100)(-1000 -100);
FORCEPROP 2 LAST SIG_NAME SMB_SCM_11_XLTR_SDA
J 0
(-2625 -90);
DISPLAY 0.489362 (-2625 -90);
WIRE 16 -1 (-1900 250)(-1900 50);
WIRE 16 -1 (-2775 50)(-1900 50);
FORCEPROP 2 LAST SIG_NAME SMB_SCM_10_XLTR_SCL
J 0
(-2625 60);
DISPLAY 0.489362 (-2625 60);
WIRE 16 -1 (-4150 600)(-4150 675);
WIRE 16 -1 (-4650 600)(-4150 600);
WIRE 16 -1 (-4650 1100)(-4650 600);
WIRE 16 -1 (-4650 1100)(-5475 1100);
FORCEPROP 2 LAST SIG_NAME PU_U5_EN
J 0
(-5310 1110);
DISPLAY 0.489362 (-5310 1110);
FORCEPROP 2 LASTPROP $XRERR UNIQUE?
J 0
(-5550 1110);
DISPLAY 0.638298 (-5550 1110);
PAINT MONO (-5550 1110);
DISPLAY INVISIBLE (-5550 1110);
WIRE 16 -1 (-3925 1250)(-3200 1250);
FORCEPROP 2 LAST SIG_NAME SMB_SCM_10_XLTR_SDA
J 2
(-3310 1260);
DISPLAY 0.489362 (-3310 1260);
WIRE 16 -1 (-3850 -1475)(-3125 -1475);
FORCEPROP 2 LAST SIG_NAME SMB_SCM_11_XLTR_SDA
J 2
(-3235 -1465);
DISPLAY 0.489362 (-3235 -1465);
DOT 1 (-6325 -800);
DOT 1 (-5250 -875);
DOT 1 (-4350 1250);
DOT 1 (-6400 1925);
DOT 1 (-4350 -1375);
DOT 1 (-5325 1850);
DOT 1 (-7150 1250);
DOT 1 (-7225 1350);
DOT 1 (-4325 1350);
DOT 1 (-4400 -1475);
DOT 1 (-6975 -1375);
DOT 1 (-6900 -1475);
FORCENOTE
INTERNAL PU
(-6125 875) 0;
DISPLAY LEFT (-6125 875);
DISPLAY 1.021277 (-6125 875);
FORCENOTE
INTERNAL PU
(-6025 -1900) 0;
DISPLAY LEFT (-6025 -1900);
DISPLAY 1.021277 (-6025 -1900);
QUIT
